FILE_TYPE = MACRO_DRAWING;
SET COLOR_WIRE YELLOW;
SET COLOR_PROP ORANGE;
SET COLOR_DOT WHITE;
SET COLOR_ARC YELLOW;
SET COLOR_BODY GREEN;
SET COLOR_NOTE PURPLE;
SET PROP_DISPLAY VALUE;
SET PAGE_NUMBER P56;
FORCEADD OFFPAGE..2
R 2
(-2000 0);
FORCEPROP 2 LAST $XR1 109 
J 0
(-2375 0);
DISPLAY 0.638298 (-2375 0);
PAINT MONO (-2375 0);
FORCEPROP 2 LAST $XR0 108 
J 0
(-2255 0);
DISPLAY 0.638298 (-2255 0);
PAINT MONO (-2255 0);
FORCEPROP 2 LAST CDS_LIB standard
J 0
(-2000 0);
PAINT MONO (-2000 0);
DISPLAY INVISIBLE (-2000 0);
FORCEPROP 1 LAST OFFPAGE TRUE
J 2
(-2325 -125);
DISPLAY 0.872340 (-2325 -125);
DISPLAY INVISIBLE (-2325 -125);
FORCEPROP 1 LAST COMMENT_BODY TRUE
J 2
(-1955 -95);
DISPLAY 0.872340 (-1955 -95);
PAINT GREEN (-1955 -95);
DISPLAY INVISIBLE (-1955 -95);
FORCEPROP 2 LAST PATH I1
J 0
(-1950 75);
DISPLAY 1.021277 (-1950 75);
DISPLAY INVISIBLE (-1950 75);
FORCEADD OFFPAGE..3
R 2
(-2000 450);
FORCEPROP 2 LAST $XR1 109 
J 0
(-2430 450);
DISPLAY 0.638298 (-2430 450);
PAINT MONO (-2430 450);
FORCEPROP 2 LAST $XR0 108 
J 0
(-2310 450);
DISPLAY 0.638298 (-2310 450);
PAINT MONO (-2310 450);
FORCEPROP 2 LAST CDS_LIB standard
J 0
(-2000 450);
DISPLAY INVISIBLE (-2000 450);
FORCEPROP 1 LAST OFFPAGE TRUE
J 2
(-2325 325);
DISPLAY 0.872340 (-2325 325);
DISPLAY INVISIBLE (-2325 325);
FORCEPROP 1 LAST COMMENT_BODY TRUE
J 2
(-1950 350);
DISPLAY 0.872340 (-1950 350);
PAINT GREEN (-1950 350);
DISPLAY INVISIBLE (-1950 350);
FORCEPROP 2 LAST PATH I10
J 0
(-1950 525);
DISPLAY 1.021277 (-1950 525);
DISPLAY INVISIBLE (-1950 525);
FORCEADD TAP..1
(2450 625);
FORCEPROP 3 LASTPIN (2400 625) SIG_NAME M_F_CPU1_SA_CS_N<1>
J 0
(2410 635);
DISPLAY 0.659574 (2410 635);
PAINT MONO (2410 635);
DISPLAY INVISIBLE (2410 635);
FORCEPROP 1 LASTPIN (2400 625) BN 1
J 0
(2388 633);
DISPLAY 0.680851 (2388 633);
PAINT GREEN (2388 633);
FORCEPROP 2 LAST CDS_LIB standard
J 0
(2450 625);
DISPLAY INVISIBLE (2450 625);
FORCEPROP 1 LAST BODY_TYPE PLUMBING
J 0
(2450 675);
DISPLAY 0.872340 (2450 675);
PAINT GREEN (2450 675);
DISPLAY INVISIBLE (2450 675);
FORCEPROP 1 LAST HDL_TAP TRUE
J 0
(2775 500);
DISPLAY 0.872340 (2775 500);
DISPLAY INVISIBLE (2775 500);
FORCEPROP 1 LAST PATH I100
J 0
(2448 625);
DISPLAY 0.872340 (2448 625);
PAINT GREEN (2448 625);
DISPLAY INVISIBLE (2448 625);
FORCEADD TAP..1
(2450 675);
FORCEPROP 3 LASTPIN (2400 675) SIG_NAME M_F_CPU1_SA_CS_N<2>
J 0
(2410 685);
DISPLAY 0.659574 (2410 685);
PAINT MONO (2410 685);
DISPLAY INVISIBLE (2410 685);
FORCEPROP 1 LASTPIN (2400 675) BN 2
J 0
(2388 683);
DISPLAY 0.680851 (2388 683);
PAINT GREEN (2388 683);
FORCEPROP 2 LAST CDS_LIB standard
J 0
(2450 675);
DISPLAY INVISIBLE (2450 675);
FORCEPROP 1 LAST BODY_TYPE PLUMBING
J 0
(2450 725);
DISPLAY 0.872340 (2450 725);
PAINT GREEN (2450 725);
DISPLAY INVISIBLE (2450 725);
FORCEPROP 1 LAST HDL_TAP TRUE
J 0
(2775 550);
DISPLAY 0.872340 (2775 550);
DISPLAY INVISIBLE (2775 550);
FORCEPROP 1 LAST PATH I101
J 0
(2448 675);
DISPLAY 0.872340 (2448 675);
PAINT GREEN (2448 675);
DISPLAY INVISIBLE (2448 675);
FORCEADD TAP..1
(2450 575);
FORCEPROP 3 LASTPIN (2400 575) SIG_NAME M_F_CPU1_SA_CS_N<0>
J 0
(2410 585);
DISPLAY 0.659574 (2410 585);
PAINT MONO (2410 585);
DISPLAY INVISIBLE (2410 585);
FORCEPROP 1 LASTPIN (2400 575) BN 0
J 0
(2388 583);
DISPLAY 0.680851 (2388 583);
PAINT GREEN (2388 583);
FORCEPROP 2 LAST CDS_LIB standard
J 0
(2450 575);
DISPLAY INVISIBLE (2450 575);
FORCEPROP 1 LAST BODY_TYPE PLUMBING
J 0
(2450 625);
DISPLAY 0.872340 (2450 625);
PAINT GREEN (2450 625);
DISPLAY INVISIBLE (2450 625);
FORCEPROP 1 LAST HDL_TAP TRUE
J 0
(2775 450);
DISPLAY 0.872340 (2775 450);
DISPLAY INVISIBLE (2775 450);
FORCEPROP 1 LAST PATH I102
J 0
(2448 575);
DISPLAY 0.872340 (2448 575);
PAINT GREEN (2448 575);
DISPLAY INVISIBLE (2448 575);
FORCEADD TAP..1
(2450 725);
FORCEPROP 3 LASTPIN (2400 725) SIG_NAME M_F_CPU1_SA_CS_N<3>
J 0
(2410 735);
DISPLAY 0.659574 (2410 735);
PAINT MONO (2410 735);
DISPLAY INVISIBLE (2410 735);
FORCEPROP 1 LASTPIN (2400 725) BN 3
J 0
(2388 733);
DISPLAY 0.680851 (2388 733);
PAINT GREEN (2388 733);
FORCEPROP 2 LAST CDS_LIB standard
J 0
(2450 725);
DISPLAY INVISIBLE (2450 725);
FORCEPROP 1 LAST BODY_TYPE PLUMBING
J 0
(2450 775);
DISPLAY 0.872340 (2450 775);
PAINT GREEN (2450 775);
DISPLAY INVISIBLE (2450 775);
FORCEPROP 1 LAST HDL_TAP TRUE
J 0
(2775 600);
DISPLAY 0.872340 (2775 600);
DISPLAY INVISIBLE (2775 600);
FORCEPROP 1 LAST PATH I103
J 0
(2448 725);
DISPLAY 0.872340 (2448 725);
PAINT GREEN (2448 725);
DISPLAY INVISIBLE (2448 725);
FORCEADD TAP..1
(2450 925);
FORCEPROP 3 LASTPIN (2400 925) SIG_NAME M_F_CPU1_SB_CA<0>
J 0
(2410 935);
DISPLAY 0.659574 (2410 935);
PAINT MONO (2410 935);
DISPLAY INVISIBLE (2410 935);
FORCEPROP 1 LASTPIN (2400 925) BN 0
J 0
(2388 933);
DISPLAY 0.680851 (2388 933);
PAINT GREEN (2388 933);
FORCEPROP 2 LAST CDS_LIB standard
J 0
(2450 925);
DISPLAY INVISIBLE (2450 925);
FORCEPROP 1 LAST BODY_TYPE PLUMBING
J 0
(2450 975);
DISPLAY 0.872340 (2450 975);
PAINT GREEN (2450 975);
DISPLAY INVISIBLE (2450 975);
FORCEPROP 1 LAST HDL_TAP TRUE
J 0
(2775 800);
DISPLAY 0.872340 (2775 800);
DISPLAY INVISIBLE (2775 800);
FORCEPROP 1 LAST PATH I104
J 0
(2448 925);
DISPLAY 0.872340 (2448 925);
PAINT GREEN (2448 925);
DISPLAY INVISIBLE (2448 925);
FORCEADD TAP..1
(2450 1025);
FORCEPROP 3 LASTPIN (2400 1025) SIG_NAME M_F_CPU1_SB_CA<2>
J 0
(2410 1035);
DISPLAY 0.659574 (2410 1035);
PAINT MONO (2410 1035);
DISPLAY INVISIBLE (2410 1035);
FORCEPROP 1 LASTPIN (2400 1025) BN 2
J 0
(2388 1033);
DISPLAY 0.680851 (2388 1033);
PAINT GREEN (2388 1033);
FORCEPROP 2 LAST CDS_LIB standard
J 0
(2450 1025);
DISPLAY INVISIBLE (2450 1025);
FORCEPROP 1 LAST BODY_TYPE PLUMBING
J 0
(2450 1075);
DISPLAY 0.872340 (2450 1075);
PAINT GREEN (2450 1075);
DISPLAY INVISIBLE (2450 1075);
FORCEPROP 1 LAST HDL_TAP TRUE
J 0
(2775 900);
DISPLAY 0.872340 (2775 900);
DISPLAY INVISIBLE (2775 900);
FORCEPROP 1 LAST PATH I105
J 0
(2448 1025);
DISPLAY 0.872340 (2448 1025);
PAINT GREEN (2448 1025);
DISPLAY INVISIBLE (2448 1025);
FORCEADD TAP..1
(2450 975);
FORCEPROP 3 LASTPIN (2400 975) SIG_NAME M_F_CPU1_SB_CA<1>
J 0
(2410 985);
DISPLAY 0.659574 (2410 985);
PAINT MONO (2410 985);
DISPLAY INVISIBLE (2410 985);
FORCEPROP 1 LASTPIN (2400 975) BN 1
J 0
(2388 983);
DISPLAY 0.680851 (2388 983);
PAINT GREEN (2388 983);
FORCEPROP 2 LAST CDS_LIB standard
J 0
(2450 975);
DISPLAY INVISIBLE (2450 975);
FORCEPROP 1 LAST BODY_TYPE PLUMBING
J 0
(2450 1025);
DISPLAY 0.872340 (2450 1025);
PAINT GREEN (2450 1025);
DISPLAY INVISIBLE (2450 1025);
FORCEPROP 1 LAST HDL_TAP TRUE
J 0
(2775 850);
DISPLAY 0.872340 (2775 850);
DISPLAY INVISIBLE (2775 850);
FORCEPROP 1 LAST PATH I106
J 0
(2448 975);
DISPLAY 0.872340 (2448 975);
PAINT GREEN (2448 975);
DISPLAY INVISIBLE (2448 975);
FORCEADD TAP..1
(2450 1175);
FORCEPROP 3 LASTPIN (2400 1175) SIG_NAME M_F_CPU1_SB_CA<5>
J 0
(2410 1185);
DISPLAY 0.659574 (2410 1185);
PAINT MONO (2410 1185);
DISPLAY INVISIBLE (2410 1185);
FORCEPROP 1 LASTPIN (2400 1175) BN 5
J 0
(2388 1183);
DISPLAY 0.680851 (2388 1183);
PAINT GREEN (2388 1183);
FORCEPROP 2 LAST CDS_LIB standard
J 0
(2450 1175);
DISPLAY INVISIBLE (2450 1175);
FORCEPROP 1 LAST BODY_TYPE PLUMBING
J 0
(2450 1225);
DISPLAY 0.872340 (2450 1225);
PAINT GREEN (2450 1225);
DISPLAY INVISIBLE (2450 1225);
FORCEPROP 1 LAST HDL_TAP TRUE
J 0
(2775 1050);
DISPLAY 0.872340 (2775 1050);
DISPLAY INVISIBLE (2775 1050);
FORCEPROP 1 LAST PATH I107
J 0
(2448 1175);
DISPLAY 0.872340 (2448 1175);
PAINT GREEN (2448 1175);
DISPLAY INVISIBLE (2448 1175);
FORCEADD TAP..1
(2450 1075);
FORCEPROP 3 LASTPIN (2400 1075) SIG_NAME M_F_CPU1_SB_CA<3>
J 0
(2410 1085);
DISPLAY 0.659574 (2410 1085);
PAINT MONO (2410 1085);
DISPLAY INVISIBLE (2410 1085);
FORCEPROP 1 LASTPIN (2400 1075) BN 3
J 0
(2388 1083);
DISPLAY 0.680851 (2388 1083);
PAINT GREEN (2388 1083);
FORCEPROP 2 LAST CDS_LIB standard
J 0
(2450 1075);
DISPLAY INVISIBLE (2450 1075);
FORCEPROP 1 LAST BODY_TYPE PLUMBING
J 0
(2450 1125);
DISPLAY 0.872340 (2450 1125);
PAINT GREEN (2450 1125);
DISPLAY INVISIBLE (2450 1125);
FORCEPROP 1 LAST HDL_TAP TRUE
J 0
(2775 950);
DISPLAY 0.872340 (2775 950);
DISPLAY INVISIBLE (2775 950);
FORCEPROP 1 LAST PATH I108
J 0
(2448 1075);
DISPLAY 0.872340 (2448 1075);
PAINT GREEN (2448 1075);
DISPLAY INVISIBLE (2448 1075);
FORCEADD TAP..1
(2450 1125);
FORCEPROP 3 LASTPIN (2400 1125) SIG_NAME M_F_CPU1_SB_CA<4>
J 0
(2410 1135);
DISPLAY 0.659574 (2410 1135);
PAINT MONO (2410 1135);
DISPLAY INVISIBLE (2410 1135);
FORCEPROP 1 LASTPIN (2400 1125) BN 4
J 0
(2388 1133);
DISPLAY 0.680851 (2388 1133);
PAINT GREEN (2388 1133);
FORCEPROP 2 LAST CDS_LIB standard
J 0
(2450 1125);
DISPLAY INVISIBLE (2450 1125);
FORCEPROP 1 LAST BODY_TYPE PLUMBING
J 0
(2450 1175);
DISPLAY 0.872340 (2450 1175);
PAINT GREEN (2450 1175);
DISPLAY INVISIBLE (2450 1175);
FORCEPROP 1 LAST HDL_TAP TRUE
J 0
(2775 1000);
DISPLAY 0.872340 (2775 1000);
DISPLAY INVISIBLE (2775 1000);
FORCEPROP 1 LAST PATH I109
J 0
(2448 1125);
DISPLAY 0.872340 (2448 1125);
PAINT GREEN (2448 1125);
DISPLAY INVISIBLE (2448 1125);
FORCEADD OFFPAGE..3
R 2
(-2000 2050);
FORCEPROP 2 LAST $XR1 109 
J 0
(-2430 2050);
DISPLAY 0.638298 (-2430 2050);
PAINT MONO (-2430 2050);
FORCEPROP 2 LAST $XR0 108 
J 0
(-2310 2050);
DISPLAY 0.638298 (-2310 2050);
PAINT MONO (-2310 2050);
FORCEPROP 2 LAST CDS_LIB standard
J 0
(-2000 2050);
DISPLAY INVISIBLE (-2000 2050);
FORCEPROP 1 LAST OFFPAGE TRUE
J 2
(-2325 1925);
DISPLAY 0.872340 (-2325 1925);
DISPLAY INVISIBLE (-2325 1925);
FORCEPROP 1 LAST COMMENT_BODY TRUE
J 2
(-1950 1950);
DISPLAY 0.872340 (-1950 1950);
PAINT GREEN (-1950 1950);
DISPLAY INVISIBLE (-1950 1950);
FORCEPROP 2 LAST PATH I11
J 0
(-1950 2125);
DISPLAY 1.021277 (-1950 2125);
DISPLAY INVISIBLE (-1950 2125);
FORCEADD TAP..1
(2450 1225);
FORCEPROP 3 LASTPIN (2400 1225) SIG_NAME M_F_CPU1_SB_CA<6>
J 0
(2410 1235);
DISPLAY 0.659574 (2410 1235);
PAINT MONO (2410 1235);
DISPLAY INVISIBLE (2410 1235);
FORCEPROP 1 LASTPIN (2400 1225) BN 6
J 0
(2388 1233);
DISPLAY 0.680851 (2388 1233);
PAINT GREEN (2388 1233);
FORCEPROP 2 LAST CDS_LIB standard
J 0
(2450 1225);
DISPLAY INVISIBLE (2450 1225);
FORCEPROP 1 LAST BODY_TYPE PLUMBING
J 0
(2450 1275);
DISPLAY 0.872340 (2450 1275);
PAINT GREEN (2450 1275);
DISPLAY INVISIBLE (2450 1275);
FORCEPROP 1 LAST HDL_TAP TRUE
J 0
(2775 1100);
DISPLAY 0.872340 (2775 1100);
DISPLAY INVISIBLE (2775 1100);
FORCEPROP 1 LAST PATH I110
J 0
(2448 1225);
DISPLAY 0.872340 (2448 1225);
PAINT GREEN (2448 1225);
DISPLAY INVISIBLE (2448 1225);
FORCEADD TAP..1
(2450 1425);
FORCEPROP 3 LASTPIN (2400 1425) SIG_NAME M_F_CPU1_SA_CA<0>
J 0
(2410 1435);
DISPLAY 0.659574 (2410 1435);
PAINT MONO (2410 1435);
DISPLAY INVISIBLE (2410 1435);
FORCEPROP 1 LASTPIN (2400 1425) BN 0
J 0
(2388 1433);
DISPLAY 0.680851 (2388 1433);
PAINT GREEN (2388 1433);
FORCEPROP 2 LAST CDS_LIB standard
J 0
(2450 1425);
DISPLAY INVISIBLE (2450 1425);
FORCEPROP 1 LAST BODY_TYPE PLUMBING
J 0
(2450 1475);
DISPLAY 0.872340 (2450 1475);
PAINT GREEN (2450 1475);
DISPLAY INVISIBLE (2450 1475);
FORCEPROP 1 LAST HDL_TAP TRUE
J 0
(2775 1300);
DISPLAY 0.872340 (2775 1300);
DISPLAY INVISIBLE (2775 1300);
FORCEPROP 1 LAST PATH I111
J 0
(2448 1425);
DISPLAY 0.872340 (2448 1425);
PAINT GREEN (2448 1425);
DISPLAY INVISIBLE (2448 1425);
FORCEADD TAP..1
(2450 1525);
FORCEPROP 3 LASTPIN (2400 1525) SIG_NAME M_F_CPU1_SA_CA<2>
J 0
(2410 1535);
DISPLAY 0.659574 (2410 1535);
PAINT MONO (2410 1535);
DISPLAY INVISIBLE (2410 1535);
FORCEPROP 1 LASTPIN (2400 1525) BN 2
J 0
(2388 1533);
DISPLAY 0.680851 (2388 1533);
PAINT GREEN (2388 1533);
FORCEPROP 2 LAST CDS_LIB standard
J 0
(2450 1525);
DISPLAY INVISIBLE (2450 1525);
FORCEPROP 1 LAST BODY_TYPE PLUMBING
J 0
(2450 1575);
DISPLAY 0.872340 (2450 1575);
PAINT GREEN (2450 1575);
DISPLAY INVISIBLE (2450 1575);
FORCEPROP 1 LAST HDL_TAP TRUE
J 0
(2775 1400);
DISPLAY 0.872340 (2775 1400);
DISPLAY INVISIBLE (2775 1400);
FORCEPROP 1 LAST PATH I112
J 0
(2448 1525);
DISPLAY 0.872340 (2448 1525);
PAINT GREEN (2448 1525);
DISPLAY INVISIBLE (2448 1525);
FORCEADD TAP..1
(2450 1475);
FORCEPROP 3 LASTPIN (2400 1475) SIG_NAME M_F_CPU1_SA_CA<1>
J 0
(2410 1485);
DISPLAY 0.659574 (2410 1485);
PAINT MONO (2410 1485);
DISPLAY INVISIBLE (2410 1485);
FORCEPROP 1 LASTPIN (2400 1475) BN 1
J 0
(2388 1483);
DISPLAY 0.680851 (2388 1483);
PAINT GREEN (2388 1483);
FORCEPROP 2 LAST CDS_LIB standard
J 0
(2450 1475);
DISPLAY INVISIBLE (2450 1475);
FORCEPROP 1 LAST BODY_TYPE PLUMBING
J 0
(2450 1525);
DISPLAY 0.872340 (2450 1525);
PAINT GREEN (2450 1525);
DISPLAY INVISIBLE (2450 1525);
FORCEPROP 1 LAST HDL_TAP TRUE
J 0
(2775 1350);
DISPLAY 0.872340 (2775 1350);
DISPLAY INVISIBLE (2775 1350);
FORCEPROP 1 LAST PATH I113
J 0
(2448 1475);
DISPLAY 0.872340 (2448 1475);
PAINT GREEN (2448 1475);
DISPLAY INVISIBLE (2448 1475);
FORCEADD TAP..1
(2450 1575);
FORCEPROP 3 LASTPIN (2400 1575) SIG_NAME M_F_CPU1_SA_CA<3>
J 0
(2410 1585);
DISPLAY 0.659574 (2410 1585);
PAINT MONO (2410 1585);
DISPLAY INVISIBLE (2410 1585);
FORCEPROP 1 LASTPIN (2400 1575) BN 3
J 0
(2388 1583);
DISPLAY 0.680851 (2388 1583);
PAINT GREEN (2388 1583);
FORCEPROP 2 LAST CDS_LIB standard
J 0
(2450 1575);
DISPLAY INVISIBLE (2450 1575);
FORCEPROP 1 LAST BODY_TYPE PLUMBING
J 0
(2450 1625);
DISPLAY 0.872340 (2450 1625);
PAINT GREEN (2450 1625);
DISPLAY INVISIBLE (2450 1625);
FORCEPROP 1 LAST HDL_TAP TRUE
J 0
(2775 1450);
DISPLAY 0.872340 (2775 1450);
DISPLAY INVISIBLE (2775 1450);
FORCEPROP 1 LAST PATH I114
J 0
(2448 1575);
DISPLAY 0.872340 (2448 1575);
PAINT GREEN (2448 1575);
DISPLAY INVISIBLE (2448 1575);
FORCEADD TAP..1
(2450 1675);
FORCEPROP 3 LASTPIN (2400 1675) SIG_NAME M_F_CPU1_SA_CA<5>
J 0
(2410 1685);
DISPLAY 0.659574 (2410 1685);
PAINT MONO (2410 1685);
DISPLAY INVISIBLE (2410 1685);
FORCEPROP 1 LASTPIN (2400 1675) BN 5
J 0
(2388 1683);
DISPLAY 0.680851 (2388 1683);
PAINT GREEN (2388 1683);
FORCEPROP 2 LAST CDS_LIB standard
J 0
(2450 1675);
DISPLAY INVISIBLE (2450 1675);
FORCEPROP 1 LAST BODY_TYPE PLUMBING
J 0
(2450 1725);
DISPLAY 0.872340 (2450 1725);
PAINT GREEN (2450 1725);
DISPLAY INVISIBLE (2450 1725);
FORCEPROP 1 LAST HDL_TAP TRUE
J 0
(2775 1550);
DISPLAY 0.872340 (2775 1550);
DISPLAY INVISIBLE (2775 1550);
FORCEPROP 1 LAST PATH I115
J 0
(2448 1675);
DISPLAY 0.872340 (2448 1675);
PAINT GREEN (2448 1675);
DISPLAY INVISIBLE (2448 1675);
FORCEADD TAP..1
(2450 1625);
FORCEPROP 3 LASTPIN (2400 1625) SIG_NAME M_F_CPU1_SA_CA<4>
J 0
(2410 1635);
DISPLAY 0.659574 (2410 1635);
PAINT MONO (2410 1635);
DISPLAY INVISIBLE (2410 1635);
FORCEPROP 1 LASTPIN (2400 1625) BN 4
J 0
(2388 1633);
DISPLAY 0.680851 (2388 1633);
PAINT GREEN (2388 1633);
FORCEPROP 2 LAST CDS_LIB standard
J 0
(2450 1625);
DISPLAY INVISIBLE (2450 1625);
FORCEPROP 1 LAST BODY_TYPE PLUMBING
J 0
(2450 1675);
DISPLAY 0.872340 (2450 1675);
PAINT GREEN (2450 1675);
DISPLAY INVISIBLE (2450 1675);
FORCEPROP 1 LAST HDL_TAP TRUE
J 0
(2775 1500);
DISPLAY 0.872340 (2775 1500);
DISPLAY INVISIBLE (2775 1500);
FORCEPROP 1 LAST PATH I116
J 0
(2448 1625);
DISPLAY 0.872340 (2448 1625);
PAINT GREEN (2448 1625);
DISPLAY INVISIBLE (2448 1625);
FORCEADD TAP..1
(2450 1725);
FORCEPROP 3 LASTPIN (2400 1725) SIG_NAME M_F_CPU1_SA_CA<6>
J 0
(2410 1735);
DISPLAY 0.659574 (2410 1735);
PAINT MONO (2410 1735);
DISPLAY INVISIBLE (2410 1735);
FORCEPROP 1 LASTPIN (2400 1725) BN 6
J 0
(2388 1733);
DISPLAY 0.680851 (2388 1733);
PAINT GREEN (2388 1733);
FORCEPROP 2 LAST CDS_LIB standard
J 0
(2450 1725);
DISPLAY INVISIBLE (2450 1725);
FORCEPROP 1 LAST BODY_TYPE PLUMBING
J 0
(2450 1775);
DISPLAY 0.872340 (2450 1775);
PAINT GREEN (2450 1775);
DISPLAY INVISIBLE (2450 1775);
FORCEPROP 1 LAST HDL_TAP TRUE
J 0
(2775 1600);
DISPLAY 0.872340 (2775 1600);
DISPLAY INVISIBLE (2775 1600);
FORCEPROP 1 LAST PATH I117
J 0
(2448 1725);
DISPLAY 0.872340 (2448 1725);
PAINT GREEN (2448 1725);
DISPLAY INVISIBLE (2448 1725);
FORCEADD TAP..1
(2450 1875);
FORCEPROP 3 LASTPIN (2400 1875) SIG_NAME M_F_CPU1_SB_DQS_DN<0>
J 0
(2410 1885);
DISPLAY 0.659574 (2410 1885);
PAINT MONO (2410 1885);
DISPLAY INVISIBLE (2410 1885);
FORCEPROP 1 LASTPIN (2400 1875) BN 0
J 0
(2388 1883);
DISPLAY 0.680851 (2388 1883);
PAINT GREEN (2388 1883);
FORCEPROP 2 LAST CDS_LIB standard
J 0
(2450 1875);
DISPLAY INVISIBLE (2450 1875);
FORCEPROP 1 LAST BODY_TYPE PLUMBING
J 0
(2450 1925);
DISPLAY 0.872340 (2450 1925);
PAINT GREEN (2450 1925);
DISPLAY INVISIBLE (2450 1925);
FORCEPROP 1 LAST HDL_TAP TRUE
J 0
(2775 1750);
DISPLAY 0.872340 (2775 1750);
DISPLAY INVISIBLE (2775 1750);
FORCEPROP 1 LAST PATH I118
J 0
(2448 1875);
DISPLAY 0.872340 (2448 1875);
PAINT GREEN (2448 1875);
DISPLAY INVISIBLE (2448 1875);
FORCEADD TAP..1
(2450 1925);
FORCEPROP 3 LASTPIN (2400 1925) SIG_NAME M_F_CPU1_SB_DQS_DN<1>
J 0
(2410 1935);
DISPLAY 0.659574 (2410 1935);
PAINT MONO (2410 1935);
DISPLAY INVISIBLE (2410 1935);
FORCEPROP 1 LASTPIN (2400 1925) BN 1
J 0
(2388 1933);
DISPLAY 0.680851 (2388 1933);
PAINT GREEN (2388 1933);
FORCEPROP 2 LAST CDS_LIB standard
J 0
(2450 1925);
DISPLAY INVISIBLE (2450 1925);
FORCEPROP 1 LAST BODY_TYPE PLUMBING
J 0
(2450 1975);
DISPLAY 0.872340 (2450 1975);
PAINT GREEN (2450 1975);
DISPLAY INVISIBLE (2450 1975);
FORCEPROP 1 LAST HDL_TAP TRUE
J 0
(2775 1800);
DISPLAY 0.872340 (2775 1800);
DISPLAY INVISIBLE (2775 1800);
FORCEPROP 1 LAST PATH I119
J 0
(2448 1925);
DISPLAY 0.872340 (2448 1925);
PAINT GREEN (2448 1925);
DISPLAY INVISIBLE (2448 1925);
FORCEADD TAP..1
R 2
(-975 275);
FORCEPROP 3 LASTPIN (-925 275) SIG_NAME M_F_CPU1_SB_CB<4>
J 0
(-915 285);
DISPLAY 0.659574 (-915 285);
PAINT MONO (-915 285);
DISPLAY INVISIBLE (-915 285);
FORCEPROP 1 LASTPIN (-925 275) BN 4
J 2
(-913 283);
DISPLAY 0.680851 (-913 283);
PAINT GREEN (-913 283);
FORCEPROP 2 LAST CDS_LIB standard
J 0
(-975 275);
DISPLAY INVISIBLE (-975 275);
FORCEPROP 1 LAST BODY_TYPE PLUMBING
J 2
(-975 325);
DISPLAY 0.872340 (-975 325);
PAINT GREEN (-975 325);
DISPLAY INVISIBLE (-975 325);
FORCEPROP 1 LAST HDL_TAP TRUE
J 2
(-1300 150);
DISPLAY 0.872340 (-1300 150);
DISPLAY INVISIBLE (-1300 150);
FORCEPROP 1 LAST PATH I12
J 2
(-973 275);
DISPLAY 0.872340 (-973 275);
PAINT GREEN (-973 275);
DISPLAY INVISIBLE (-973 275);
FORCEADD TAP..1
(2450 1975);
FORCEPROP 3 LASTPIN (2400 1975) SIG_NAME M_F_CPU1_SB_DQS_DN<2>
J 0
(2410 1985);
DISPLAY 0.659574 (2410 1985);
PAINT MONO (2410 1985);
DISPLAY INVISIBLE (2410 1985);
FORCEPROP 1 LASTPIN (2400 1975) BN 2
J 0
(2388 1983);
DISPLAY 0.680851 (2388 1983);
PAINT GREEN (2388 1983);
FORCEPROP 2 LAST CDS_LIB standard
J 0
(2450 1975);
DISPLAY INVISIBLE (2450 1975);
FORCEPROP 1 LAST BODY_TYPE PLUMBING
J 0
(2450 2025);
DISPLAY 0.872340 (2450 2025);
PAINT GREEN (2450 2025);
DISPLAY INVISIBLE (2450 2025);
FORCEPROP 1 LAST HDL_TAP TRUE
J 0
(2775 1850);
DISPLAY 0.872340 (2775 1850);
DISPLAY INVISIBLE (2775 1850);
FORCEPROP 1 LAST PATH I120
J 0
(2448 1975);
DISPLAY 0.872340 (2448 1975);
PAINT GREEN (2448 1975);
DISPLAY INVISIBLE (2448 1975);
FORCEADD TAP..1
(2450 2025);
FORCEPROP 3 LASTPIN (2400 2025) SIG_NAME M_F_CPU1_SB_DQS_DN<3>
J 0
(2410 2035);
DISPLAY 0.659574 (2410 2035);
PAINT MONO (2410 2035);
DISPLAY INVISIBLE (2410 2035);
FORCEPROP 1 LASTPIN (2400 2025) BN 3
J 0
(2388 2033);
DISPLAY 0.680851 (2388 2033);
PAINT GREEN (2388 2033);
FORCEPROP 2 LAST CDS_LIB standard
J 0
(2450 2025);
DISPLAY INVISIBLE (2450 2025);
FORCEPROP 1 LAST BODY_TYPE PLUMBING
J 0
(2450 2075);
DISPLAY 0.872340 (2450 2075);
PAINT GREEN (2450 2075);
DISPLAY INVISIBLE (2450 2075);
FORCEPROP 1 LAST HDL_TAP TRUE
J 0
(2775 1900);
DISPLAY 0.872340 (2775 1900);
DISPLAY INVISIBLE (2775 1900);
FORCEPROP 1 LAST PATH I121
J 0
(2448 2025);
DISPLAY 0.872340 (2448 2025);
PAINT GREEN (2448 2025);
DISPLAY INVISIBLE (2448 2025);
FORCEADD TAP..1
(2450 2075);
FORCEPROP 3 LASTPIN (2400 2075) SIG_NAME M_F_CPU1_SB_DQS_DN<4>
J 0
(2410 2085);
DISPLAY 0.659574 (2410 2085);
PAINT MONO (2410 2085);
DISPLAY INVISIBLE (2410 2085);
FORCEPROP 1 LASTPIN (2400 2075) BN 4
J 0
(2388 2083);
DISPLAY 0.680851 (2388 2083);
PAINT GREEN (2388 2083);
FORCEPROP 2 LAST CDS_LIB standard
J 0
(2450 2075);
DISPLAY INVISIBLE (2450 2075);
FORCEPROP 1 LAST BODY_TYPE PLUMBING
J 0
(2450 2125);
DISPLAY 0.872340 (2450 2125);
PAINT GREEN (2450 2125);
DISPLAY INVISIBLE (2450 2125);
FORCEPROP 1 LAST HDL_TAP TRUE
J 0
(2775 1950);
DISPLAY 0.872340 (2775 1950);
DISPLAY INVISIBLE (2775 1950);
FORCEPROP 1 LAST PATH I122
J 0
(2448 2075);
DISPLAY 0.872340 (2448 2075);
PAINT GREEN (2448 2075);
DISPLAY INVISIBLE (2448 2075);
FORCEADD TAP..1
(2450 2175);
FORCEPROP 3 LASTPIN (2400 2175) SIG_NAME M_F_CPU1_SB_DQS_DN<6>
J 0
(2410 2185);
DISPLAY 0.659574 (2410 2185);
PAINT MONO (2410 2185);
DISPLAY INVISIBLE (2410 2185);
FORCEPROP 1 LASTPIN (2400 2175) BN 6
J 0
(2388 2183);
DISPLAY 0.680851 (2388 2183);
PAINT GREEN (2388 2183);
FORCEPROP 2 LAST CDS_LIB standard
J 0
(2450 2175);
DISPLAY INVISIBLE (2450 2175);
FORCEPROP 1 LAST BODY_TYPE PLUMBING
J 0
(2450 2225);
DISPLAY 0.872340 (2450 2225);
PAINT GREEN (2450 2225);
DISPLAY INVISIBLE (2450 2225);
FORCEPROP 1 LAST HDL_TAP TRUE
J 0
(2775 2050);
DISPLAY 0.872340 (2775 2050);
DISPLAY INVISIBLE (2775 2050);
FORCEPROP 1 LAST PATH I123
J 0
(2448 2175);
DISPLAY 0.872340 (2448 2175);
PAINT GREEN (2448 2175);
DISPLAY INVISIBLE (2448 2175);
FORCEADD TAP..1
(2450 2125);
FORCEPROP 3 LASTPIN (2400 2125) SIG_NAME M_F_CPU1_SB_DQS_DN<5>
J 0
(2410 2135);
DISPLAY 0.659574 (2410 2135);
PAINT MONO (2410 2135);
DISPLAY INVISIBLE (2410 2135);
FORCEPROP 1 LASTPIN (2400 2125) BN 5
J 0
(2388 2133);
DISPLAY 0.680851 (2388 2133);
PAINT GREEN (2388 2133);
FORCEPROP 2 LAST CDS_LIB standard
J 0
(2450 2125);
DISPLAY INVISIBLE (2450 2125);
FORCEPROP 1 LAST BODY_TYPE PLUMBING
J 0
(2450 2175);
DISPLAY 0.872340 (2450 2175);
PAINT GREEN (2450 2175);
DISPLAY INVISIBLE (2450 2175);
FORCEPROP 1 LAST HDL_TAP TRUE
J 0
(2775 2000);
DISPLAY 0.872340 (2775 2000);
DISPLAY INVISIBLE (2775 2000);
FORCEPROP 1 LAST PATH I124
J 0
(2448 2125);
DISPLAY 0.872340 (2448 2125);
PAINT GREEN (2448 2125);
DISPLAY INVISIBLE (2448 2125);
FORCEADD TAP..1
(2450 2325);
FORCEPROP 3 LASTPIN (2400 2325) SIG_NAME M_F_CPU1_SB_DQS_DN<9>
J 0
(2410 2335);
DISPLAY 0.659574 (2410 2335);
PAINT MONO (2410 2335);
DISPLAY INVISIBLE (2410 2335);
FORCEPROP 1 LASTPIN (2400 2325) BN 9
J 0
(2388 2333);
DISPLAY 0.680851 (2388 2333);
PAINT GREEN (2388 2333);
FORCEPROP 2 LAST CDS_LIB standard
J 0
(2450 2325);
DISPLAY INVISIBLE (2450 2325);
FORCEPROP 1 LAST BODY_TYPE PLUMBING
J 0
(2450 2375);
DISPLAY 0.872340 (2450 2375);
PAINT GREEN (2450 2375);
DISPLAY INVISIBLE (2450 2375);
FORCEPROP 1 LAST HDL_TAP TRUE
J 0
(2775 2200);
DISPLAY 0.872340 (2775 2200);
DISPLAY INVISIBLE (2775 2200);
FORCEPROP 1 LAST PATH I125
J 0
(2448 2325);
DISPLAY 0.872340 (2448 2325);
PAINT GREEN (2448 2325);
DISPLAY INVISIBLE (2448 2325);
FORCEADD TAP..1
(2450 2275);
FORCEPROP 3 LASTPIN (2400 2275) SIG_NAME M_F_CPU1_SB_DQS_DN<8>
J 0
(2410 2285);
DISPLAY 0.659574 (2410 2285);
PAINT MONO (2410 2285);
DISPLAY INVISIBLE (2410 2285);
FORCEPROP 1 LASTPIN (2400 2275) BN 8
J 0
(2388 2283);
DISPLAY 0.680851 (2388 2283);
PAINT GREEN (2388 2283);
FORCEPROP 2 LAST CDS_LIB standard
J 0
(2450 2275);
DISPLAY INVISIBLE (2450 2275);
FORCEPROP 1 LAST BODY_TYPE PLUMBING
J 0
(2450 2325);
DISPLAY 0.872340 (2450 2325);
PAINT GREEN (2450 2325);
DISPLAY INVISIBLE (2450 2325);
FORCEPROP 1 LAST HDL_TAP TRUE
J 0
(2775 2150);
DISPLAY 0.872340 (2775 2150);
DISPLAY INVISIBLE (2775 2150);
FORCEPROP 1 LAST PATH I126
J 0
(2448 2275);
DISPLAY 0.872340 (2448 2275);
PAINT GREEN (2448 2275);
DISPLAY INVISIBLE (2448 2275);
FORCEADD TAP..1
(2450 2225);
FORCEPROP 3 LASTPIN (2400 2225) SIG_NAME M_F_CPU1_SB_DQS_DN<7>
J 0
(2410 2235);
DISPLAY 0.659574 (2410 2235);
PAINT MONO (2410 2235);
DISPLAY INVISIBLE (2410 2235);
FORCEPROP 1 LASTPIN (2400 2225) BN 7
J 0
(2388 2233);
DISPLAY 0.680851 (2388 2233);
PAINT GREEN (2388 2233);
FORCEPROP 2 LAST CDS_LIB standard
J 0
(2450 2225);
DISPLAY INVISIBLE (2450 2225);
FORCEPROP 1 LAST BODY_TYPE PLUMBING
J 0
(2450 2275);
DISPLAY 0.872340 (2450 2275);
PAINT GREEN (2450 2275);
DISPLAY INVISIBLE (2450 2275);
FORCEPROP 1 LAST HDL_TAP TRUE
J 0
(2775 2100);
DISPLAY 0.872340 (2775 2100);
DISPLAY INVISIBLE (2775 2100);
FORCEPROP 1 LAST PATH I127
J 0
(2448 2225);
DISPLAY 0.872340 (2448 2225);
PAINT GREEN (2448 2225);
DISPLAY INVISIBLE (2448 2225);
FORCEADD TAP..1
(2450 2425);
FORCEPROP 3 LASTPIN (2400 2425) SIG_NAME M_F_CPU1_SB_DQS_DP<0>
J 0
(2410 2435);
DISPLAY 0.659574 (2410 2435);
PAINT MONO (2410 2435);
DISPLAY INVISIBLE (2410 2435);
FORCEPROP 1 LASTPIN (2400 2425) BN 0
J 0
(2388 2433);
DISPLAY 0.680851 (2388 2433);
PAINT GREEN (2388 2433);
FORCEPROP 2 LAST CDS_LIB standard
J 0
(2450 2425);
DISPLAY INVISIBLE (2450 2425);
FORCEPROP 1 LAST BODY_TYPE PLUMBING
J 0
(2450 2475);
DISPLAY 0.872340 (2450 2475);
PAINT GREEN (2450 2475);
DISPLAY INVISIBLE (2450 2475);
FORCEPROP 1 LAST HDL_TAP TRUE
J 0
(2775 2300);
DISPLAY 0.872340 (2775 2300);
DISPLAY INVISIBLE (2775 2300);
FORCEPROP 1 LAST PATH I128
J 0
(2448 2425);
DISPLAY 0.872340 (2448 2425);
PAINT GREEN (2448 2425);
DISPLAY INVISIBLE (2448 2425);
FORCEADD TAP..1
(2450 2475);
FORCEPROP 3 LASTPIN (2400 2475) SIG_NAME M_F_CPU1_SB_DQS_DP<1>
J 0
(2410 2485);
DISPLAY 0.659574 (2410 2485);
PAINT MONO (2410 2485);
DISPLAY INVISIBLE (2410 2485);
FORCEPROP 1 LASTPIN (2400 2475) BN 1
J 0
(2388 2483);
DISPLAY 0.680851 (2388 2483);
PAINT GREEN (2388 2483);
FORCEPROP 2 LAST CDS_LIB standard
J 0
(2450 2475);
DISPLAY INVISIBLE (2450 2475);
FORCEPROP 1 LAST BODY_TYPE PLUMBING
J 0
(2450 2525);
DISPLAY 0.872340 (2450 2525);
PAINT GREEN (2450 2525);
DISPLAY INVISIBLE (2450 2525);
FORCEPROP 1 LAST HDL_TAP TRUE
J 0
(2775 2350);
DISPLAY 0.872340 (2775 2350);
DISPLAY INVISIBLE (2775 2350);
FORCEPROP 1 LAST PATH I129
J 0
(2448 2475);
DISPLAY 0.872340 (2448 2475);
PAINT GREEN (2448 2475);
DISPLAY INVISIBLE (2448 2475);
FORCEADD TAP..1
R 2
(-975 225);
FORCEPROP 3 LASTPIN (-925 225) SIG_NAME M_F_CPU1_SB_CB<3>
J 0
(-915 235);
DISPLAY 0.659574 (-915 235);
PAINT MONO (-915 235);
DISPLAY INVISIBLE (-915 235);
FORCEPROP 1 LASTPIN (-925 225) BN 3
J 2
(-913 233);
DISPLAY 0.680851 (-913 233);
PAINT GREEN (-913 233);
FORCEPROP 2 LAST CDS_LIB standard
J 0
(-975 225);
DISPLAY INVISIBLE (-975 225);
FORCEPROP 1 LAST BODY_TYPE PLUMBING
J 2
(-975 275);
DISPLAY 0.872340 (-975 275);
PAINT GREEN (-975 275);
DISPLAY INVISIBLE (-975 275);
FORCEPROP 1 LAST HDL_TAP TRUE
J 2
(-1300 100);
DISPLAY 0.872340 (-1300 100);
DISPLAY INVISIBLE (-1300 100);
FORCEPROP 1 LAST PATH I13
J 2
(-973 225);
DISPLAY 0.872340 (-973 225);
PAINT GREEN (-973 225);
DISPLAY INVISIBLE (-973 225);
FORCEADD TAP..1
(2450 2525);
FORCEPROP 3 LASTPIN (2400 2525) SIG_NAME M_F_CPU1_SB_DQS_DP<2>
J 0
(2410 2535);
DISPLAY 0.659574 (2410 2535);
PAINT MONO (2410 2535);
DISPLAY INVISIBLE (2410 2535);
FORCEPROP 1 LASTPIN (2400 2525) BN 2
J 0
(2388 2533);
DISPLAY 0.680851 (2388 2533);
PAINT GREEN (2388 2533);
FORCEPROP 2 LAST CDS_LIB standard
J 0
(2450 2525);
DISPLAY INVISIBLE (2450 2525);
FORCEPROP 1 LAST BODY_TYPE PLUMBING
J 0
(2450 2575);
DISPLAY 0.872340 (2450 2575);
PAINT GREEN (2450 2575);
DISPLAY INVISIBLE (2450 2575);
FORCEPROP 1 LAST HDL_TAP TRUE
J 0
(2775 2400);
DISPLAY 0.872340 (2775 2400);
DISPLAY INVISIBLE (2775 2400);
FORCEPROP 1 LAST PATH I130
J 0
(2448 2525);
DISPLAY 0.872340 (2448 2525);
PAINT GREEN (2448 2525);
DISPLAY INVISIBLE (2448 2525);
FORCEADD TAP..1
(2450 2575);
FORCEPROP 3 LASTPIN (2400 2575) SIG_NAME M_F_CPU1_SB_DQS_DP<3>
J 0
(2410 2585);
DISPLAY 0.659574 (2410 2585);
PAINT MONO (2410 2585);
DISPLAY INVISIBLE (2410 2585);
FORCEPROP 1 LASTPIN (2400 2575) BN 3
J 0
(2388 2583);
DISPLAY 0.680851 (2388 2583);
PAINT GREEN (2388 2583);
FORCEPROP 2 LAST CDS_LIB standard
J 0
(2450 2575);
DISPLAY INVISIBLE (2450 2575);
FORCEPROP 1 LAST BODY_TYPE PLUMBING
J 0
(2450 2625);
DISPLAY 0.872340 (2450 2625);
PAINT GREEN (2450 2625);
DISPLAY INVISIBLE (2450 2625);
FORCEPROP 1 LAST HDL_TAP TRUE
J 0
(2775 2450);
DISPLAY 0.872340 (2775 2450);
DISPLAY INVISIBLE (2775 2450);
FORCEPROP 1 LAST PATH I131
J 0
(2448 2575);
DISPLAY 0.872340 (2448 2575);
PAINT GREEN (2448 2575);
DISPLAY INVISIBLE (2448 2575);
FORCEADD TAP..1
(2450 2725);
FORCEPROP 3 LASTPIN (2400 2725) SIG_NAME M_F_CPU1_SB_DQS_DP<6>
J 0
(2410 2735);
DISPLAY 0.659574 (2410 2735);
PAINT MONO (2410 2735);
DISPLAY INVISIBLE (2410 2735);
FORCEPROP 1 LASTPIN (2400 2725) BN 6
J 0
(2388 2733);
DISPLAY 0.680851 (2388 2733);
PAINT GREEN (2388 2733);
FORCEPROP 2 LAST CDS_LIB standard
J 0
(2450 2725);
DISPLAY INVISIBLE (2450 2725);
FORCEPROP 1 LAST BODY_TYPE PLUMBING
J 0
(2450 2775);
DISPLAY 0.872340 (2450 2775);
PAINT GREEN (2450 2775);
DISPLAY INVISIBLE (2450 2775);
FORCEPROP 1 LAST HDL_TAP TRUE
J 0
(2775 2600);
DISPLAY 0.872340 (2775 2600);
DISPLAY INVISIBLE (2775 2600);
FORCEPROP 1 LAST PATH I132
J 0
(2448 2725);
DISPLAY 0.872340 (2448 2725);
PAINT GREEN (2448 2725);
DISPLAY INVISIBLE (2448 2725);
FORCEADD TAP..1
(2450 2625);
FORCEPROP 3 LASTPIN (2400 2625) SIG_NAME M_F_CPU1_SB_DQS_DP<4>
J 0
(2410 2635);
DISPLAY 0.659574 (2410 2635);
PAINT MONO (2410 2635);
DISPLAY INVISIBLE (2410 2635);
FORCEPROP 1 LASTPIN (2400 2625) BN 4
J 0
(2388 2633);
DISPLAY 0.680851 (2388 2633);
PAINT GREEN (2388 2633);
FORCEPROP 2 LAST CDS_LIB standard
J 0
(2450 2625);
DISPLAY INVISIBLE (2450 2625);
FORCEPROP 1 LAST BODY_TYPE PLUMBING
J 0
(2450 2675);
DISPLAY 0.872340 (2450 2675);
PAINT GREEN (2450 2675);
DISPLAY INVISIBLE (2450 2675);
FORCEPROP 1 LAST HDL_TAP TRUE
J 0
(2775 2500);
DISPLAY 0.872340 (2775 2500);
DISPLAY INVISIBLE (2775 2500);
FORCEPROP 1 LAST PATH I133
J 0
(2448 2625);
DISPLAY 0.872340 (2448 2625);
PAINT GREEN (2448 2625);
DISPLAY INVISIBLE (2448 2625);
FORCEADD TAP..1
(2450 2675);
FORCEPROP 3 LASTPIN (2400 2675) SIG_NAME M_F_CPU1_SB_DQS_DP<5>
J 0
(2410 2685);
DISPLAY 0.659574 (2410 2685);
PAINT MONO (2410 2685);
DISPLAY INVISIBLE (2410 2685);
FORCEPROP 1 LASTPIN (2400 2675) BN 5
J 0
(2388 2683);
DISPLAY 0.680851 (2388 2683);
PAINT GREEN (2388 2683);
FORCEPROP 2 LAST CDS_LIB standard
J 0
(2450 2675);
DISPLAY INVISIBLE (2450 2675);
FORCEPROP 1 LAST BODY_TYPE PLUMBING
J 0
(2450 2725);
DISPLAY 0.872340 (2450 2725);
PAINT GREEN (2450 2725);
DISPLAY INVISIBLE (2450 2725);
FORCEPROP 1 LAST HDL_TAP TRUE
J 0
(2775 2550);
DISPLAY 0.872340 (2775 2550);
DISPLAY INVISIBLE (2775 2550);
FORCEPROP 1 LAST PATH I134
J 0
(2448 2675);
DISPLAY 0.872340 (2448 2675);
PAINT GREEN (2448 2675);
DISPLAY INVISIBLE (2448 2675);
FORCEADD TAP..1
(2450 2825);
FORCEPROP 3 LASTPIN (2400 2825) SIG_NAME M_F_CPU1_SB_DQS_DP<8>
J 0
(2410 2835);
DISPLAY 0.659574 (2410 2835);
PAINT MONO (2410 2835);
DISPLAY INVISIBLE (2410 2835);
FORCEPROP 1 LASTPIN (2400 2825) BN 8
J 0
(2388 2833);
DISPLAY 0.680851 (2388 2833);
PAINT GREEN (2388 2833);
FORCEPROP 2 LAST CDS_LIB standard
J 0
(2450 2825);
DISPLAY INVISIBLE (2450 2825);
FORCEPROP 1 LAST BODY_TYPE PLUMBING
J 0
(2450 2875);
DISPLAY 0.872340 (2450 2875);
PAINT GREEN (2450 2875);
DISPLAY INVISIBLE (2450 2875);
FORCEPROP 1 LAST HDL_TAP TRUE
J 0
(2775 2700);
DISPLAY 0.872340 (2775 2700);
DISPLAY INVISIBLE (2775 2700);
FORCEPROP 1 LAST PATH I135
J 0
(2448 2825);
DISPLAY 0.872340 (2448 2825);
PAINT GREEN (2448 2825);
DISPLAY INVISIBLE (2448 2825);
FORCEADD TAP..1
(2450 2875);
FORCEPROP 3 LASTPIN (2400 2875) SIG_NAME M_F_CPU1_SB_DQS_DP<9>
J 0
(2410 2885);
DISPLAY 0.659574 (2410 2885);
PAINT MONO (2410 2885);
DISPLAY INVISIBLE (2410 2885);
FORCEPROP 1 LASTPIN (2400 2875) BN 9
J 0
(2388 2883);
DISPLAY 0.680851 (2388 2883);
PAINT GREEN (2388 2883);
FORCEPROP 2 LAST CDS_LIB standard
J 0
(2450 2875);
DISPLAY INVISIBLE (2450 2875);
FORCEPROP 1 LAST BODY_TYPE PLUMBING
J 0
(2450 2925);
DISPLAY 0.872340 (2450 2925);
PAINT GREEN (2450 2925);
DISPLAY INVISIBLE (2450 2925);
FORCEPROP 1 LAST HDL_TAP TRUE
J 0
(2775 2750);
DISPLAY 0.872340 (2775 2750);
DISPLAY INVISIBLE (2775 2750);
FORCEPROP 1 LAST PATH I136
J 0
(2448 2875);
DISPLAY 0.872340 (2448 2875);
PAINT GREEN (2448 2875);
DISPLAY INVISIBLE (2448 2875);
FORCEADD TAP..1
(2450 2775);
FORCEPROP 3 LASTPIN (2400 2775) SIG_NAME M_F_CPU1_SB_DQS_DP<7>
J 0
(2410 2785);
DISPLAY 0.659574 (2410 2785);
PAINT MONO (2410 2785);
DISPLAY INVISIBLE (2410 2785);
FORCEPROP 1 LASTPIN (2400 2775) BN 7
J 0
(2388 2783);
DISPLAY 0.680851 (2388 2783);
PAINT GREEN (2388 2783);
FORCEPROP 2 LAST CDS_LIB standard
J 0
(2450 2775);
DISPLAY INVISIBLE (2450 2775);
FORCEPROP 1 LAST BODY_TYPE PLUMBING
J 0
(2450 2825);
DISPLAY 0.872340 (2450 2825);
PAINT GREEN (2450 2825);
DISPLAY INVISIBLE (2450 2825);
FORCEPROP 1 LAST HDL_TAP TRUE
J 0
(2775 2650);
DISPLAY 0.872340 (2775 2650);
DISPLAY INVISIBLE (2775 2650);
FORCEPROP 1 LAST PATH I137
J 0
(2448 2775);
DISPLAY 0.872340 (2448 2775);
PAINT GREEN (2448 2775);
DISPLAY INVISIBLE (2448 2775);
FORCEADD TAP..1
(2450 3075);
FORCEPROP 3 LASTPIN (2400 3075) SIG_NAME M_F_CPU1_SA_DQS_DN<1>
J 0
(2410 3085);
DISPLAY 0.659574 (2410 3085);
PAINT MONO (2410 3085);
DISPLAY INVISIBLE (2410 3085);
FORCEPROP 1 LASTPIN (2400 3075) BN 1
J 0
(2388 3083);
DISPLAY 0.680851 (2388 3083);
PAINT GREEN (2388 3083);
FORCEPROP 2 LAST CDS_LIB standard
J 0
(2450 3075);
DISPLAY INVISIBLE (2450 3075);
FORCEPROP 1 LAST BODY_TYPE PLUMBING
J 0
(2450 3125);
DISPLAY 0.872340 (2450 3125);
PAINT GREEN (2450 3125);
DISPLAY INVISIBLE (2450 3125);
FORCEPROP 1 LAST HDL_TAP TRUE
J 0
(2775 2950);
DISPLAY 0.872340 (2775 2950);
DISPLAY INVISIBLE (2775 2950);
FORCEPROP 1 LAST PATH I138
J 0
(2448 3075);
DISPLAY 0.872340 (2448 3075);
PAINT GREEN (2448 3075);
DISPLAY INVISIBLE (2448 3075);
FORCEADD TAP..1
(2450 3025);
FORCEPROP 3 LASTPIN (2400 3025) SIG_NAME M_F_CPU1_SA_DQS_DN<0>
J 0
(2410 3035);
DISPLAY 0.659574 (2410 3035);
PAINT MONO (2410 3035);
DISPLAY INVISIBLE (2410 3035);
FORCEPROP 1 LASTPIN (2400 3025) BN 0
J 0
(2388 3033);
DISPLAY 0.680851 (2388 3033);
PAINT GREEN (2388 3033);
FORCEPROP 2 LAST CDS_LIB standard
J 0
(2450 3025);
DISPLAY INVISIBLE (2450 3025);
FORCEPROP 1 LAST BODY_TYPE PLUMBING
J 0
(2450 3075);
DISPLAY 0.872340 (2450 3075);
PAINT GREEN (2450 3075);
DISPLAY INVISIBLE (2450 3075);
FORCEPROP 1 LAST HDL_TAP TRUE
J 0
(2775 2900);
DISPLAY 0.872340 (2775 2900);
DISPLAY INVISIBLE (2775 2900);
FORCEPROP 1 LAST PATH I139
J 0
(2448 3025);
DISPLAY 0.872340 (2448 3025);
PAINT GREEN (2448 3025);
DISPLAY INVISIBLE (2448 3025);
FORCEADD TAP..1
R 2
(-975 375);
FORCEPROP 3 LASTPIN (-925 375) SIG_NAME M_F_CPU1_SB_CB<6>
J 0
(-915 385);
DISPLAY 0.659574 (-915 385);
PAINT MONO (-915 385);
DISPLAY INVISIBLE (-915 385);
FORCEPROP 1 LASTPIN (-925 375) BN 6
J 2
(-913 383);
DISPLAY 0.680851 (-913 383);
PAINT GREEN (-913 383);
FORCEPROP 2 LAST CDS_LIB standard
J 0
(-975 375);
DISPLAY INVISIBLE (-975 375);
FORCEPROP 1 LAST BODY_TYPE PLUMBING
J 2
(-975 425);
DISPLAY 0.872340 (-975 425);
PAINT GREEN (-975 425);
DISPLAY INVISIBLE (-975 425);
FORCEPROP 1 LAST HDL_TAP TRUE
J 2
(-1300 250);
DISPLAY 0.872340 (-1300 250);
DISPLAY INVISIBLE (-1300 250);
FORCEPROP 1 LAST PATH I14
J 2
(-973 375);
DISPLAY 0.872340 (-973 375);
PAINT GREEN (-973 375);
DISPLAY INVISIBLE (-973 375);
FORCEADD TAP..1
(2450 3225);
FORCEPROP 3 LASTPIN (2400 3225) SIG_NAME M_F_CPU1_SA_DQS_DN<4>
J 0
(2410 3235);
DISPLAY 0.659574 (2410 3235);
PAINT MONO (2410 3235);
DISPLAY INVISIBLE (2410 3235);
FORCEPROP 1 LASTPIN (2400 3225) BN 4
J 0
(2388 3233);
DISPLAY 0.680851 (2388 3233);
PAINT GREEN (2388 3233);
FORCEPROP 2 LAST CDS_LIB standard
J 0
(2450 3225);
DISPLAY INVISIBLE (2450 3225);
FORCEPROP 1 LAST BODY_TYPE PLUMBING
J 0
(2450 3275);
DISPLAY 0.872340 (2450 3275);
PAINT GREEN (2450 3275);
DISPLAY INVISIBLE (2450 3275);
FORCEPROP 1 LAST HDL_TAP TRUE
J 0
(2775 3100);
DISPLAY 0.872340 (2775 3100);
DISPLAY INVISIBLE (2775 3100);
FORCEPROP 1 LAST PATH I140
J 0
(2448 3225);
DISPLAY 0.872340 (2448 3225);
PAINT GREEN (2448 3225);
DISPLAY INVISIBLE (2448 3225);
FORCEADD TAP..1
(2450 3125);
FORCEPROP 3 LASTPIN (2400 3125) SIG_NAME M_F_CPU1_SA_DQS_DN<2>
J 0
(2410 3135);
DISPLAY 0.659574 (2410 3135);
PAINT MONO (2410 3135);
DISPLAY INVISIBLE (2410 3135);
FORCEPROP 1 LASTPIN (2400 3125) BN 2
J 0
(2388 3133);
DISPLAY 0.680851 (2388 3133);
PAINT GREEN (2388 3133);
FORCEPROP 2 LAST CDS_LIB standard
J 0
(2450 3125);
DISPLAY INVISIBLE (2450 3125);
FORCEPROP 1 LAST BODY_TYPE PLUMBING
J 0
(2450 3175);
DISPLAY 0.872340 (2450 3175);
PAINT GREEN (2450 3175);
DISPLAY INVISIBLE (2450 3175);
FORCEPROP 1 LAST HDL_TAP TRUE
J 0
(2775 3000);
DISPLAY 0.872340 (2775 3000);
DISPLAY INVISIBLE (2775 3000);
FORCEPROP 1 LAST PATH I141
J 0
(2448 3125);
DISPLAY 0.872340 (2448 3125);
PAINT GREEN (2448 3125);
DISPLAY INVISIBLE (2448 3125);
FORCEADD TAP..1
(2450 3175);
FORCEPROP 3 LASTPIN (2400 3175) SIG_NAME M_F_CPU1_SA_DQS_DN<3>
J 0
(2410 3185);
DISPLAY 0.659574 (2410 3185);
PAINT MONO (2410 3185);
DISPLAY INVISIBLE (2410 3185);
FORCEPROP 1 LASTPIN (2400 3175) BN 3
J 0
(2388 3183);
DISPLAY 0.680851 (2388 3183);
PAINT GREEN (2388 3183);
FORCEPROP 2 LAST CDS_LIB standard
J 0
(2450 3175);
DISPLAY INVISIBLE (2450 3175);
FORCEPROP 1 LAST BODY_TYPE PLUMBING
J 0
(2450 3225);
DISPLAY 0.872340 (2450 3225);
PAINT GREEN (2450 3225);
DISPLAY INVISIBLE (2450 3225);
FORCEPROP 1 LAST HDL_TAP TRUE
J 0
(2775 3050);
DISPLAY 0.872340 (2775 3050);
DISPLAY INVISIBLE (2775 3050);
FORCEPROP 1 LAST PATH I142
J 0
(2448 3175);
DISPLAY 0.872340 (2448 3175);
PAINT GREEN (2448 3175);
DISPLAY INVISIBLE (2448 3175);
FORCEADD TAP..1
(2450 3275);
FORCEPROP 3 LASTPIN (2400 3275) SIG_NAME M_F_CPU1_SA_DQS_DN<5>
J 0
(2410 3285);
DISPLAY 0.659574 (2410 3285);
PAINT MONO (2410 3285);
DISPLAY INVISIBLE (2410 3285);
FORCEPROP 1 LASTPIN (2400 3275) BN 5
J 0
(2388 3283);
DISPLAY 0.680851 (2388 3283);
PAINT GREEN (2388 3283);
FORCEPROP 2 LAST CDS_LIB standard
J 0
(2450 3275);
DISPLAY INVISIBLE (2450 3275);
FORCEPROP 1 LAST BODY_TYPE PLUMBING
J 0
(2450 3325);
DISPLAY 0.872340 (2450 3325);
PAINT GREEN (2450 3325);
DISPLAY INVISIBLE (2450 3325);
FORCEPROP 1 LAST HDL_TAP TRUE
J 0
(2775 3150);
DISPLAY 0.872340 (2775 3150);
DISPLAY INVISIBLE (2775 3150);
FORCEPROP 1 LAST PATH I143
J 0
(2448 3275);
DISPLAY 0.872340 (2448 3275);
PAINT GREEN (2448 3275);
DISPLAY INVISIBLE (2448 3275);
FORCEADD TAP..1
(2450 3325);
FORCEPROP 3 LASTPIN (2400 3325) SIG_NAME M_F_CPU1_SA_DQS_DN<6>
J 0
(2410 3335);
DISPLAY 0.659574 (2410 3335);
PAINT MONO (2410 3335);
DISPLAY INVISIBLE (2410 3335);
FORCEPROP 1 LASTPIN (2400 3325) BN 6
J 0
(2388 3333);
DISPLAY 0.680851 (2388 3333);
PAINT GREEN (2388 3333);
FORCEPROP 2 LAST CDS_LIB standard
J 0
(2450 3325);
DISPLAY INVISIBLE (2450 3325);
FORCEPROP 1 LAST BODY_TYPE PLUMBING
J 0
(2450 3375);
DISPLAY 0.872340 (2450 3375);
PAINT GREEN (2450 3375);
DISPLAY INVISIBLE (2450 3375);
FORCEPROP 1 LAST HDL_TAP TRUE
J 0
(2775 3200);
DISPLAY 0.872340 (2775 3200);
DISPLAY INVISIBLE (2775 3200);
FORCEPROP 1 LAST PATH I144
J 0
(2448 3325);
DISPLAY 0.872340 (2448 3325);
PAINT GREEN (2448 3325);
DISPLAY INVISIBLE (2448 3325);
FORCEADD TAP..1
(2450 3375);
FORCEPROP 3 LASTPIN (2400 3375) SIG_NAME M_F_CPU1_SA_DQS_DN<7>
J 0
(2410 3385);
DISPLAY 0.659574 (2410 3385);
PAINT MONO (2410 3385);
DISPLAY INVISIBLE (2410 3385);
FORCEPROP 1 LASTPIN (2400 3375) BN 7
J 0
(2388 3383);
DISPLAY 0.680851 (2388 3383);
PAINT GREEN (2388 3383);
FORCEPROP 2 LAST CDS_LIB standard
J 0
(2450 3375);
DISPLAY INVISIBLE (2450 3375);
FORCEPROP 1 LAST BODY_TYPE PLUMBING
J 0
(2450 3425);
DISPLAY 0.872340 (2450 3425);
PAINT GREEN (2450 3425);
DISPLAY INVISIBLE (2450 3425);
FORCEPROP 1 LAST HDL_TAP TRUE
J 0
(2775 3250);
DISPLAY 0.872340 (2775 3250);
DISPLAY INVISIBLE (2775 3250);
FORCEPROP 1 LAST PATH I145
J 0
(2448 3375);
DISPLAY 0.872340 (2448 3375);
PAINT GREEN (2448 3375);
DISPLAY INVISIBLE (2448 3375);
FORCEADD TAP..1
(2450 3475);
FORCEPROP 3 LASTPIN (2400 3475) SIG_NAME M_F_CPU1_SA_DQS_DN<9>
J 0
(2410 3485);
DISPLAY 0.659574 (2410 3485);
PAINT MONO (2410 3485);
DISPLAY INVISIBLE (2410 3485);
FORCEPROP 1 LASTPIN (2400 3475) BN 9
J 0
(2388 3483);
DISPLAY 0.680851 (2388 3483);
PAINT GREEN (2388 3483);
FORCEPROP 2 LAST CDS_LIB standard
J 0
(2450 3475);
DISPLAY INVISIBLE (2450 3475);
FORCEPROP 1 LAST BODY_TYPE PLUMBING
J 0
(2450 3525);
DISPLAY 0.872340 (2450 3525);
PAINT GREEN (2450 3525);
DISPLAY INVISIBLE (2450 3525);
FORCEPROP 1 LAST HDL_TAP TRUE
J 0
(2775 3350);
DISPLAY 0.872340 (2775 3350);
DISPLAY INVISIBLE (2775 3350);
FORCEPROP 1 LAST PATH I146
J 0
(2448 3475);
DISPLAY 0.872340 (2448 3475);
PAINT GREEN (2448 3475);
DISPLAY INVISIBLE (2448 3475);
FORCEADD TAP..1
(2450 3425);
FORCEPROP 3 LASTPIN (2400 3425) SIG_NAME M_F_CPU1_SA_DQS_DN<8>
J 0
(2410 3435);
DISPLAY 0.659574 (2410 3435);
PAINT MONO (2410 3435);
DISPLAY INVISIBLE (2410 3435);
FORCEPROP 1 LASTPIN (2400 3425) BN 8
J 0
(2388 3433);
DISPLAY 0.680851 (2388 3433);
PAINT GREEN (2388 3433);
FORCEPROP 2 LAST CDS_LIB standard
J 0
(2450 3425);
DISPLAY INVISIBLE (2450 3425);
FORCEPROP 1 LAST BODY_TYPE PLUMBING
J 0
(2450 3475);
DISPLAY 0.872340 (2450 3475);
PAINT GREEN (2450 3475);
DISPLAY INVISIBLE (2450 3475);
FORCEPROP 1 LAST HDL_TAP TRUE
J 0
(2775 3300);
DISPLAY 0.872340 (2775 3300);
DISPLAY INVISIBLE (2775 3300);
FORCEPROP 1 LAST PATH I147
J 0
(2448 3425);
DISPLAY 0.872340 (2448 3425);
PAINT GREEN (2448 3425);
DISPLAY INVISIBLE (2448 3425);
FORCEADD TAP..1
(2450 3575);
FORCEPROP 3 LASTPIN (2400 3575) SIG_NAME M_F_CPU1_SA_DQS_DP<0>
J 0
(2410 3585);
DISPLAY 0.659574 (2410 3585);
PAINT MONO (2410 3585);
DISPLAY INVISIBLE (2410 3585);
FORCEPROP 1 LASTPIN (2400 3575) BN 0
J 0
(2388 3583);
DISPLAY 0.680851 (2388 3583);
PAINT GREEN (2388 3583);
FORCEPROP 2 LAST CDS_LIB standard
J 0
(2450 3575);
DISPLAY INVISIBLE (2450 3575);
FORCEPROP 1 LAST BODY_TYPE PLUMBING
J 0
(2450 3625);
DISPLAY 0.872340 (2450 3625);
PAINT GREEN (2450 3625);
DISPLAY INVISIBLE (2450 3625);
FORCEPROP 1 LAST HDL_TAP TRUE
J 0
(2775 3450);
DISPLAY 0.872340 (2775 3450);
DISPLAY INVISIBLE (2775 3450);
FORCEPROP 1 LAST PATH I148
J 0
(2448 3575);
DISPLAY 0.872340 (2448 3575);
PAINT GREEN (2448 3575);
DISPLAY INVISIBLE (2448 3575);
FORCEADD TAP..1
(2450 3625);
FORCEPROP 3 LASTPIN (2400 3625) SIG_NAME M_F_CPU1_SA_DQS_DP<1>
J 0
(2410 3635);
DISPLAY 0.659574 (2410 3635);
PAINT MONO (2410 3635);
DISPLAY INVISIBLE (2410 3635);
FORCEPROP 1 LASTPIN (2400 3625) BN 1
J 0
(2388 3633);
DISPLAY 0.680851 (2388 3633);
PAINT GREEN (2388 3633);
FORCEPROP 2 LAST CDS_LIB standard
J 0
(2450 3625);
DISPLAY INVISIBLE (2450 3625);
FORCEPROP 1 LAST BODY_TYPE PLUMBING
J 0
(2450 3675);
DISPLAY 0.872340 (2450 3675);
PAINT GREEN (2450 3675);
DISPLAY INVISIBLE (2450 3675);
FORCEPROP 1 LAST HDL_TAP TRUE
J 0
(2775 3500);
DISPLAY 0.872340 (2775 3500);
DISPLAY INVISIBLE (2775 3500);
FORCEPROP 1 LAST PATH I149
J 0
(2448 3625);
DISPLAY 0.872340 (2448 3625);
PAINT GREEN (2448 3625);
DISPLAY INVISIBLE (2448 3625);
FORCEADD TAP..1
R 2
(-975 325);
FORCEPROP 3 LASTPIN (-925 325) SIG_NAME M_F_CPU1_SB_CB<5>
J 0
(-915 335);
DISPLAY 0.659574 (-915 335);
PAINT MONO (-915 335);
DISPLAY INVISIBLE (-915 335);
FORCEPROP 1 LASTPIN (-925 325) BN 5
J 2
(-913 333);
DISPLAY 0.680851 (-913 333);
PAINT GREEN (-913 333);
FORCEPROP 2 LAST CDS_LIB standard
J 0
(-975 325);
DISPLAY INVISIBLE (-975 325);
FORCEPROP 1 LAST BODY_TYPE PLUMBING
J 2
(-975 375);
DISPLAY 0.872340 (-975 375);
PAINT GREEN (-975 375);
DISPLAY INVISIBLE (-975 375);
FORCEPROP 1 LAST HDL_TAP TRUE
J 2
(-1300 200);
DISPLAY 0.872340 (-1300 200);
DISPLAY INVISIBLE (-1300 200);
FORCEPROP 1 LAST PATH I15
J 2
(-973 325);
DISPLAY 0.872340 (-973 325);
PAINT GREEN (-973 325);
DISPLAY INVISIBLE (-973 325);
FORCEADD TAP..1
(2450 3725);
FORCEPROP 3 LASTPIN (2400 3725) SIG_NAME M_F_CPU1_SA_DQS_DP<3>
J 0
(2410 3735);
DISPLAY 0.659574 (2410 3735);
PAINT MONO (2410 3735);
DISPLAY INVISIBLE (2410 3735);
FORCEPROP 1 LASTPIN (2400 3725) BN 3
J 0
(2388 3733);
DISPLAY 0.680851 (2388 3733);
PAINT GREEN (2388 3733);
FORCEPROP 2 LAST CDS_LIB standard
J 0
(2450 3725);
DISPLAY INVISIBLE (2450 3725);
FORCEPROP 1 LAST BODY_TYPE PLUMBING
J 0
(2450 3775);
DISPLAY 0.872340 (2450 3775);
PAINT GREEN (2450 3775);
DISPLAY INVISIBLE (2450 3775);
FORCEPROP 1 LAST HDL_TAP TRUE
J 0
(2775 3600);
DISPLAY 0.872340 (2775 3600);
DISPLAY INVISIBLE (2775 3600);
FORCEPROP 1 LAST PATH I150
J 0
(2448 3725);
DISPLAY 0.872340 (2448 3725);
PAINT GREEN (2448 3725);
DISPLAY INVISIBLE (2448 3725);
FORCEADD TAP..1
(2450 3675);
FORCEPROP 3 LASTPIN (2400 3675) SIG_NAME M_F_CPU1_SA_DQS_DP<2>
J 0
(2410 3685);
DISPLAY 0.659574 (2410 3685);
PAINT MONO (2410 3685);
DISPLAY INVISIBLE (2410 3685);
FORCEPROP 1 LASTPIN (2400 3675) BN 2
J 0
(2388 3683);
DISPLAY 0.680851 (2388 3683);
PAINT GREEN (2388 3683);
FORCEPROP 2 LAST CDS_LIB standard
J 0
(2450 3675);
DISPLAY INVISIBLE (2450 3675);
FORCEPROP 1 LAST BODY_TYPE PLUMBING
J 0
(2450 3725);
DISPLAY 0.872340 (2450 3725);
PAINT GREEN (2450 3725);
DISPLAY INVISIBLE (2450 3725);
FORCEPROP 1 LAST HDL_TAP TRUE
J 0
(2775 3550);
DISPLAY 0.872340 (2775 3550);
DISPLAY INVISIBLE (2775 3550);
FORCEPROP 1 LAST PATH I151
J 0
(2448 3675);
DISPLAY 0.872340 (2448 3675);
PAINT GREEN (2448 3675);
DISPLAY INVISIBLE (2448 3675);
FORCEADD TAP..1
(2450 3775);
FORCEPROP 3 LASTPIN (2400 3775) SIG_NAME M_F_CPU1_SA_DQS_DP<4>
J 0
(2410 3785);
DISPLAY 0.659574 (2410 3785);
PAINT MONO (2410 3785);
DISPLAY INVISIBLE (2410 3785);
FORCEPROP 1 LASTPIN (2400 3775) BN 4
J 0
(2388 3783);
DISPLAY 0.680851 (2388 3783);
PAINT GREEN (2388 3783);
FORCEPROP 2 LAST CDS_LIB standard
J 0
(2450 3775);
DISPLAY INVISIBLE (2450 3775);
FORCEPROP 1 LAST BODY_TYPE PLUMBING
J 0
(2450 3825);
DISPLAY 0.872340 (2450 3825);
PAINT GREEN (2450 3825);
DISPLAY INVISIBLE (2450 3825);
FORCEPROP 1 LAST HDL_TAP TRUE
J 0
(2775 3650);
DISPLAY 0.872340 (2775 3650);
DISPLAY INVISIBLE (2775 3650);
FORCEPROP 1 LAST PATH I152
J 0
(2448 3775);
DISPLAY 0.872340 (2448 3775);
PAINT GREEN (2448 3775);
DISPLAY INVISIBLE (2448 3775);
FORCEADD TAP..1
(2450 3825);
FORCEPROP 3 LASTPIN (2400 3825) SIG_NAME M_F_CPU1_SA_DQS_DP<5>
J 0
(2410 3835);
DISPLAY 0.659574 (2410 3835);
PAINT MONO (2410 3835);
DISPLAY INVISIBLE (2410 3835);
FORCEPROP 1 LASTPIN (2400 3825) BN 5
J 0
(2388 3833);
DISPLAY 0.680851 (2388 3833);
PAINT GREEN (2388 3833);
FORCEPROP 2 LAST CDS_LIB standard
J 0
(2450 3825);
DISPLAY INVISIBLE (2450 3825);
FORCEPROP 1 LAST BODY_TYPE PLUMBING
J 0
(2450 3875);
DISPLAY 0.872340 (2450 3875);
PAINT GREEN (2450 3875);
DISPLAY INVISIBLE (2450 3875);
FORCEPROP 1 LAST HDL_TAP TRUE
J 0
(2775 3700);
DISPLAY 0.872340 (2775 3700);
DISPLAY INVISIBLE (2775 3700);
FORCEPROP 1 LAST PATH I153
J 0
(2448 3825);
DISPLAY 0.872340 (2448 3825);
PAINT GREEN (2448 3825);
DISPLAY INVISIBLE (2448 3825);
FORCEADD TAP..1
(2450 3875);
FORCEPROP 3 LASTPIN (2400 3875) SIG_NAME M_F_CPU1_SA_DQS_DP<6>
J 0
(2410 3885);
DISPLAY 0.659574 (2410 3885);
PAINT MONO (2410 3885);
DISPLAY INVISIBLE (2410 3885);
FORCEPROP 1 LASTPIN (2400 3875) BN 6
J 0
(2388 3883);
DISPLAY 0.680851 (2388 3883);
PAINT GREEN (2388 3883);
FORCEPROP 2 LAST CDS_LIB standard
J 0
(2450 3875);
DISPLAY INVISIBLE (2450 3875);
FORCEPROP 1 LAST BODY_TYPE PLUMBING
J 0
(2450 3925);
DISPLAY 0.872340 (2450 3925);
PAINT GREEN (2450 3925);
DISPLAY INVISIBLE (2450 3925);
FORCEPROP 1 LAST HDL_TAP TRUE
J 0
(2775 3750);
DISPLAY 0.872340 (2775 3750);
DISPLAY INVISIBLE (2775 3750);
FORCEPROP 1 LAST PATH I154
J 0
(2448 3875);
DISPLAY 0.872340 (2448 3875);
PAINT GREEN (2448 3875);
DISPLAY INVISIBLE (2448 3875);
FORCEADD TAP..1
(2450 3975);
FORCEPROP 3 LASTPIN (2400 3975) SIG_NAME M_F_CPU1_SA_DQS_DP<8>
J 0
(2410 3985);
DISPLAY 0.659574 (2410 3985);
PAINT MONO (2410 3985);
DISPLAY INVISIBLE (2410 3985);
FORCEPROP 1 LASTPIN (2400 3975) BN 8
J 0
(2388 3983);
DISPLAY 0.680851 (2388 3983);
PAINT GREEN (2388 3983);
FORCEPROP 2 LAST CDS_LIB standard
J 0
(2450 3975);
DISPLAY INVISIBLE (2450 3975);
FORCEPROP 1 LAST BODY_TYPE PLUMBING
J 0
(2450 4025);
DISPLAY 0.872340 (2450 4025);
PAINT GREEN (2450 4025);
DISPLAY INVISIBLE (2450 4025);
FORCEPROP 1 LAST HDL_TAP TRUE
J 0
(2775 3850);
DISPLAY 0.872340 (2775 3850);
DISPLAY INVISIBLE (2775 3850);
FORCEPROP 1 LAST PATH I155
J 0
(2448 3975);
DISPLAY 0.872340 (2448 3975);
PAINT GREEN (2448 3975);
DISPLAY INVISIBLE (2448 3975);
FORCEADD TAP..1
(2450 3925);
FORCEPROP 3 LASTPIN (2400 3925) SIG_NAME M_F_CPU1_SA_DQS_DP<7>
J 0
(2410 3935);
DISPLAY 0.659574 (2410 3935);
PAINT MONO (2410 3935);
DISPLAY INVISIBLE (2410 3935);
FORCEPROP 1 LASTPIN (2400 3925) BN 7
J 0
(2388 3933);
DISPLAY 0.680851 (2388 3933);
PAINT GREEN (2388 3933);
FORCEPROP 2 LAST CDS_LIB standard
J 0
(2450 3925);
DISPLAY INVISIBLE (2450 3925);
FORCEPROP 1 LAST BODY_TYPE PLUMBING
J 0
(2450 3975);
DISPLAY 0.872340 (2450 3975);
PAINT GREEN (2450 3975);
DISPLAY INVISIBLE (2450 3975);
FORCEPROP 1 LAST HDL_TAP TRUE
J 0
(2775 3800);
DISPLAY 0.872340 (2775 3800);
DISPLAY INVISIBLE (2775 3800);
FORCEPROP 1 LAST PATH I156
J 0
(2448 3925);
DISPLAY 0.872340 (2448 3925);
PAINT GREEN (2448 3925);
DISPLAY INVISIBLE (2448 3925);
FORCEADD TAP..1
(2450 4025);
FORCEPROP 3 LASTPIN (2400 4025) SIG_NAME M_F_CPU1_SA_DQS_DP<9>
J 0
(2410 4035);
DISPLAY 0.659574 (2410 4035);
PAINT MONO (2410 4035);
DISPLAY INVISIBLE (2410 4035);
FORCEPROP 1 LASTPIN (2400 4025) BN 9
J 0
(2388 4033);
DISPLAY 0.680851 (2388 4033);
PAINT GREEN (2388 4033);
FORCEPROP 2 LAST CDS_LIB standard
J 0
(2450 4025);
DISPLAY INVISIBLE (2450 4025);
FORCEPROP 1 LAST BODY_TYPE PLUMBING
J 0
(2450 4075);
DISPLAY 0.872340 (2450 4075);
PAINT GREEN (2450 4075);
DISPLAY INVISIBLE (2450 4075);
FORCEPROP 1 LAST HDL_TAP TRUE
J 0
(2775 3900);
DISPLAY 0.872340 (2775 3900);
DISPLAY INVISIBLE (2775 3900);
FORCEPROP 1 LAST PATH I157
J 0
(2448 4025);
DISPLAY 0.872340 (2448 4025);
PAINT GREEN (2448 4025);
DISPLAY INVISIBLE (2448 4025);
FORCEADD OFFPAGE..2
(3550 450);
FORCEPROP 2 LAST $XR1 109 
J 0
(3859 450);
DISPLAY 0.638298 (3859 450);
PAINT MONO (3859 450);
FORCEPROP 2 LAST $XR0 108 
J 0
(3739 450);
DISPLAY 0.638298 (3739 450);
PAINT MONO (3739 450);
FORCEPROP 2 LAST CDS_LIB standard
J 0
(3550 450);
PAINT MONO (3550 450);
DISPLAY INVISIBLE (3550 450);
FORCEPROP 1 LAST OFFPAGE TRUE
J 0
(3875 325);
DISPLAY 1.170213 (3875 325);
PAINT GREEN (3875 325);
DISPLAY INVISIBLE (3875 325);
FORCEPROP 1 LAST COMMENT_BODY TRUE
J 0
(3505 355);
DISPLAY 1.170213 (3505 355);
PAINT GREEN (3505 355);
DISPLAY INVISIBLE (3505 355);
FORCEPROP 2 LAST PATH I158
J 0
(3725 525);
DISPLAY 1.021277 (3725 525);
DISPLAY INVISIBLE (3725 525);
FORCEADD OFFPAGE..2
(3550 750);
FORCEPROP 2 LAST $XR1 109 
J 0
(3859 750);
DISPLAY 0.638298 (3859 750);
PAINT MONO (3859 750);
FORCEPROP 2 LAST $XR0 108 
J 0
(3739 750);
DISPLAY 0.638298 (3739 750);
PAINT MONO (3739 750);
FORCEPROP 2 LAST CDS_LIB standard
J 0
(3550 750);
PAINT MONO (3550 750);
DISPLAY INVISIBLE (3550 750);
FORCEPROP 1 LAST OFFPAGE TRUE
J 0
(3875 625);
DISPLAY 1.170213 (3875 625);
PAINT GREEN (3875 625);
DISPLAY INVISIBLE (3875 625);
FORCEPROP 1 LAST COMMENT_BODY TRUE
J 0
(3505 655);
DISPLAY 1.170213 (3505 655);
PAINT GREEN (3505 655);
DISPLAY INVISIBLE (3505 655);
FORCEPROP 2 LAST PATH I159
J 0
(3725 825);
DISPLAY 1.021277 (3725 825);
DISPLAY INVISIBLE (3725 825);
FORCEADD TAP..1
R 2
(-975 475);
FORCEPROP 3 LASTPIN (-925 475) SIG_NAME M_F_CPU1_SB_DQ<0>
J 0
(-915 485);
DISPLAY 0.659574 (-915 485);
PAINT MONO (-915 485);
DISPLAY INVISIBLE (-915 485);
FORCEPROP 1 LASTPIN (-925 475) BN 0
J 2
(-913 483);
DISPLAY 0.680851 (-913 483);
PAINT GREEN (-913 483);
FORCEPROP 2 LAST CDS_LIB standard
J 0
(-975 475);
DISPLAY INVISIBLE (-975 475);
FORCEPROP 1 LAST BODY_TYPE PLUMBING
J 2
(-975 525);
DISPLAY 0.872340 (-975 525);
PAINT GREEN (-975 525);
DISPLAY INVISIBLE (-975 525);
FORCEPROP 1 LAST HDL_TAP TRUE
J 2
(-1300 350);
DISPLAY 0.872340 (-1300 350);
DISPLAY INVISIBLE (-1300 350);
FORCEPROP 1 LAST PATH I16
J 2
(-973 475);
DISPLAY 0.872340 (-973 475);
PAINT GREEN (-973 475);
DISPLAY INVISIBLE (-973 475);
FORCEADD OFFPAGE..2
(3550 875);
FORCEPROP 2 LAST $XR1 109 
J 0
(3859 875);
DISPLAY 0.638298 (3859 875);
PAINT MONO (3859 875);
FORCEPROP 2 LAST $XR0 108 
J 0
(3739 875);
DISPLAY 0.638298 (3739 875);
PAINT MONO (3739 875);
FORCEPROP 2 LAST CDS_LIB standard
J 0
(3550 875);
PAINT MONO (3550 875);
DISPLAY INVISIBLE (3550 875);
FORCEPROP 1 LAST OFFPAGE TRUE
J 0
(3875 750);
DISPLAY 1.170213 (3875 750);
PAINT GREEN (3875 750);
DISPLAY INVISIBLE (3875 750);
FORCEPROP 1 LAST COMMENT_BODY TRUE
J 0
(3505 780);
DISPLAY 1.170213 (3505 780);
PAINT GREEN (3505 780);
DISPLAY INVISIBLE (3505 780);
FORCEPROP 2 LAST PATH I160
J 0
(3725 950);
DISPLAY 1.021277 (3725 950);
DISPLAY INVISIBLE (3725 950);
FORCEADD OFFPAGE..3
(3550 1250);
FORCEPROP 2 LAST $XR1 109 
J 0
(3884 1250);
DISPLAY 0.638298 (3884 1250);
PAINT MONO (3884 1250);
FORCEPROP 2 LAST $XR0 108 
J 0
(3764 1250);
DISPLAY 0.638298 (3764 1250);
PAINT MONO (3764 1250);
FORCEPROP 2 LAST CDS_LIB standard
J 2
(3550 1250);
DISPLAY INVISIBLE (3550 1250);
FORCEPROP 1 LAST OFFPAGE TRUE
J 0
(3875 1125);
DISPLAY 0.872340 (3875 1125);
DISPLAY INVISIBLE (3875 1125);
FORCEPROP 1 LAST COMMENT_BODY TRUE
J 0
(3500 1150);
DISPLAY 0.872340 (3500 1150);
PAINT GREEN (3500 1150);
DISPLAY INVISIBLE (3500 1150);
FORCEPROP 2 LAST PATH I161
J 0
(3750 1325);
DISPLAY 1.021277 (3750 1325);
DISPLAY INVISIBLE (3750 1325);
FORCEADD OFFPAGE..2
(3550 1375);
FORCEPROP 2 LAST $XR1 109 
J 0
(3859 1375);
DISPLAY 0.638298 (3859 1375);
PAINT MONO (3859 1375);
FORCEPROP 2 LAST $XR0 108 
J 0
(3739 1375);
DISPLAY 0.638298 (3739 1375);
PAINT MONO (3739 1375);
FORCEPROP 2 LAST CDS_LIB standard
J 0
(3550 1375);
PAINT MONO (3550 1375);
DISPLAY INVISIBLE (3550 1375);
FORCEPROP 1 LAST OFFPAGE TRUE
J 0
(3875 1250);
DISPLAY 1.170213 (3875 1250);
PAINT GREEN (3875 1250);
DISPLAY INVISIBLE (3875 1250);
FORCEPROP 1 LAST COMMENT_BODY TRUE
J 0
(3505 1280);
DISPLAY 1.170213 (3505 1280);
PAINT GREEN (3505 1280);
DISPLAY INVISIBLE (3505 1280);
FORCEPROP 2 LAST PATH I162
J 0
(3725 1450);
DISPLAY 1.021277 (3725 1450);
DISPLAY INVISIBLE (3725 1450);
FORCEADD OFFPAGE..3
(3550 1750);
FORCEPROP 2 LAST $XR1 109 
J 0
(3884 1750);
DISPLAY 0.638298 (3884 1750);
PAINT MONO (3884 1750);
FORCEPROP 2 LAST $XR0 108 
J 0
(3764 1750);
DISPLAY 0.638298 (3764 1750);
PAINT MONO (3764 1750);
FORCEPROP 2 LAST CDS_LIB standard
J 2
(3550 1750);
DISPLAY INVISIBLE (3550 1750);
FORCEPROP 1 LAST OFFPAGE TRUE
J 0
(3875 1625);
DISPLAY 0.872340 (3875 1625);
DISPLAY INVISIBLE (3875 1625);
FORCEPROP 1 LAST COMMENT_BODY TRUE
J 0
(3500 1650);
DISPLAY 0.872340 (3500 1650);
PAINT GREEN (3500 1650);
DISPLAY INVISIBLE (3500 1650);
FORCEPROP 2 LAST PATH I163
J 0
(3750 1825);
DISPLAY 1.021277 (3750 1825);
DISPLAY INVISIBLE (3750 1825);
FORCEADD OFFPAGE..3
(3550 2350);
FORCEPROP 2 LAST $XR1 109 
J 0
(3884 2350);
DISPLAY 0.638298 (3884 2350);
PAINT MONO (3884 2350);
FORCEPROP 2 LAST $XR0 108 
J 0
(3764 2350);
DISPLAY 0.638298 (3764 2350);
PAINT MONO (3764 2350);
FORCEPROP 2 LAST CDS_LIB standard
J 2
(3550 2350);
DISPLAY INVISIBLE (3550 2350);
FORCEPROP 1 LAST OFFPAGE TRUE
J 0
(3875 2225);
DISPLAY 0.872340 (3875 2225);
DISPLAY INVISIBLE (3875 2225);
FORCEPROP 1 LAST COMMENT_BODY TRUE
J 0
(3500 2250);
DISPLAY 0.872340 (3500 2250);
PAINT GREEN (3500 2250);
DISPLAY INVISIBLE (3500 2250);
FORCEPROP 2 LAST PATH I164
J 0
(3750 2425);
DISPLAY 1.021277 (3750 2425);
DISPLAY INVISIBLE (3750 2425);
FORCEADD OFFPAGE..3
(3550 2900);
FORCEPROP 2 LAST $XR1 109 
J 0
(3884 2900);
DISPLAY 0.638298 (3884 2900);
PAINT MONO (3884 2900);
FORCEPROP 2 LAST $XR0 108 
J 0
(3764 2900);
DISPLAY 0.638298 (3764 2900);
PAINT MONO (3764 2900);
FORCEPROP 2 LAST CDS_LIB standard
J 2
(3550 2900);
DISPLAY INVISIBLE (3550 2900);
FORCEPROP 1 LAST OFFPAGE TRUE
J 0
(3875 2775);
DISPLAY 0.872340 (3875 2775);
DISPLAY INVISIBLE (3875 2775);
FORCEPROP 1 LAST COMMENT_BODY TRUE
J 0
(3500 2800);
DISPLAY 0.872340 (3500 2800);
PAINT GREEN (3500 2800);
DISPLAY INVISIBLE (3500 2800);
FORCEPROP 2 LAST PATH I165
J 0
(3750 2975);
DISPLAY 1.021277 (3750 2975);
DISPLAY INVISIBLE (3750 2975);
FORCEADD OFFPAGE..3
(3550 3500);
FORCEPROP 2 LAST $XR1 109 
J 0
(3884 3500);
DISPLAY 0.638298 (3884 3500);
PAINT MONO (3884 3500);
FORCEPROP 2 LAST $XR0 108 
J 0
(3764 3500);
DISPLAY 0.638298 (3764 3500);
PAINT MONO (3764 3500);
FORCEPROP 2 LAST CDS_LIB standard
J 2
(3550 3500);
DISPLAY INVISIBLE (3550 3500);
FORCEPROP 1 LAST OFFPAGE TRUE
J 0
(3875 3375);
DISPLAY 0.872340 (3875 3375);
DISPLAY INVISIBLE (3875 3375);
FORCEPROP 1 LAST COMMENT_BODY TRUE
J 0
(3500 3400);
DISPLAY 0.872340 (3500 3400);
PAINT GREEN (3500 3400);
DISPLAY INVISIBLE (3500 3400);
FORCEPROP 2 LAST PATH I166
J 0
(3750 3575);
DISPLAY 1.021277 (3750 3575);
DISPLAY INVISIBLE (3750 3575);
FORCEADD OFFPAGE..3
(3550 4050);
FORCEPROP 2 LAST $XR1 109 
J 0
(3884 4050);
DISPLAY 0.638298 (3884 4050);
PAINT MONO (3884 4050);
FORCEPROP 2 LAST $XR0 108 
J 0
(3764 4050);
DISPLAY 0.638298 (3764 4050);
PAINT MONO (3764 4050);
FORCEPROP 2 LAST CDS_LIB standard
J 2
(3550 4050);
DISPLAY INVISIBLE (3550 4050);
FORCEPROP 1 LAST OFFPAGE TRUE
J 0
(3875 3925);
DISPLAY 0.872340 (3875 3925);
DISPLAY INVISIBLE (3875 3925);
FORCEPROP 1 LAST COMMENT_BODY TRUE
J 0
(3500 3950);
DISPLAY 0.872340 (3500 3950);
PAINT GREEN (3500 3950);
DISPLAY INVISIBLE (3500 3950);
FORCEPROP 2 LAST PATH I167
J 0
(3750 4125);
DISPLAY 1.021277 (3750 4125);
DISPLAY INVISIBLE (3750 4125);
FORCEADD SOCKET4677_AZIF0045P001C01CS..13
(750 1925);
FORCEPROP 1 LAST PART_NUMBER DGA^7000023
J 0
(-350 4275);
DISPLAY 0.723404 (-350 4275);
PAINT GREEN (-350 4275);
DISPLAY INVISIBLE (-350 4275);
FORCEPROP 2 LAST PART_TYPE SMLF
J 0
(-350 4450);
DISPLAY 1.021277 (-350 4450);
FORCEPROP 1 LAST MATERIAL IO
J 0
(-350 4200);
DISPLAY 0.723404 (-350 4200);
PAINT GREEN (-350 4200);
FORCEPROP 2 LAST VALUE SOCKET4677_AZIF0045-P001C01CS
J 0
(-350 4400);
DISPLAY 1.021277 (-350 4400);
FORCEPROP 1 LAST $LOCATION U1
J 0
(-350 4350);
DISPLAY 0.723404 (-350 4350);
PAINT GREEN (-350 4350);
FORCEPROP 0 LASTPIN (1975 75) $PN DN48
J 0
(1985 85);
DISPLAY 0.680851 (1985 85);
PAINT MONO (1985 85);
FORCEPROP 0 LASTPIN (1975 125) $PN DP47
J 0
(1985 135);
DISPLAY 0.680851 (1985 135);
PAINT MONO (1985 135);
FORCEPROP 0 LASTPIN (1975 -175) $PN CW48
J 0
(1985 -165);
DISPLAY 0.680851 (1985 -165);
PAINT MONO (1985 -165);
FORCEPROP 0 LASTPIN (1975 -75) $PN DL48
J 0
(1985 -65);
DISPLAY 0.680851 (1985 -65);
PAINT MONO (1985 -65);
FORCEPROP 0 LASTPIN (1975 -25) $PN DK47
J 0
(1985 -15);
DISPLAY 0.680851 (1985 -15);
PAINT MONO (1985 -15);
FORCEPROP 0 LASTPIN (-475 -175) $PN DY49
J 2
(-485 -165);
DISPLAY 0.680851 (-485 -165);
PAINT MONO (-485 -165);
FORCEPROP 0 LASTPIN (-475 -125) $PN DV49
J 2
(-485 -115);
DISPLAY 0.680851 (-485 -115);
PAINT MONO (-485 -115);
FORCEPROP 0 LASTPIN (-475 -75) $PN EB49
J 2
(-485 -65);
DISPLAY 0.680851 (-485 -65);
PAINT MONO (-485 -65);
FORCEPROP 0 LASTPIN (-475 -25) $PN DT49
J 2
(-485 -15);
DISPLAY 0.680851 (-485 -15);
PAINT MONO (-485 -15);
FORCEPROP 0 LASTPIN (1975 1425) $PN EC52
J 0
(1985 1435);
DISPLAY 0.680851 (1985 1435);
PAINT MONO (1985 1435);
FORCEPROP 0 LASTPIN (1975 1475) $PN EJ52
J 0
(1985 1485);
DISPLAY 0.680851 (1985 1485);
PAINT MONO (1985 1485);
FORCEPROP 0 LASTPIN (1975 1525) $PN ED51
J 0
(1985 1535);
DISPLAY 0.680851 (1985 1535);
PAINT MONO (1985 1535);
FORCEPROP 0 LASTPIN (1975 1575) $PN EH51
J 0
(1985 1585);
DISPLAY 0.680851 (1985 1585);
PAINT MONO (1985 1585);
FORCEPROP 0 LASTPIN (1975 1625) $PN EE50
J 0
(1985 1635);
DISPLAY 0.680851 (1985 1635);
PAINT MONO (1985 1635);
FORCEPROP 0 LASTPIN (1975 1675) $PN EG50
J 0
(1985 1685);
DISPLAY 0.680851 (1985 1685);
PAINT MONO (1985 1685);
FORCEPROP 0 LASTPIN (1975 1725) $PN DY51
J 0
(1985 1735);
DISPLAY 0.680851 (1985 1735);
PAINT MONO (1985 1735);
FORCEPROP 0 LASTPIN (-475 2475) $PN EB77
J 2
(-485 2485);
DISPLAY 0.680851 (-485 2485);
PAINT MONO (-485 2485);
FORCEPROP 0 LASTPIN (-475 2525) $PN EH77
J 2
(-485 2535);
DISPLAY 0.680851 (-485 2535);
PAINT MONO (-485 2535);
FORCEPROP 0 LASTPIN (-475 2575) $PN ED77
J 2
(-485 2585);
DISPLAY 0.680851 (-485 2585);
PAINT MONO (-485 2585);
FORCEPROP 0 LASTPIN (-475 2625) $PN EG78
J 2
(-485 2635);
DISPLAY 0.680851 (-485 2635);
PAINT MONO (-485 2635);
FORCEPROP 0 LASTPIN (-475 2675) $PN ED75
J 2
(-485 2685);
DISPLAY 0.680851 (-485 2685);
PAINT MONO (-485 2685);
FORCEPROP 0 LASTPIN (-475 2725) $PN EE74
J 2
(-485 2735);
DISPLAY 0.680851 (-485 2735);
PAINT MONO (-485 2735);
FORCEPROP 0 LASTPIN (-475 2775) $PN EH75
J 2
(-485 2785);
DISPLAY 0.680851 (-485 2785);
PAINT MONO (-485 2785);
FORCEPROP 0 LASTPIN (-475 2825) $PN EG74
J 2
(-485 2835);
DISPLAY 0.680851 (-485 2835);
PAINT MONO (-485 2835);
FORCEPROP 0 LASTPIN (-475 2875) $PN DV69
J 2
(-485 2885);
DISPLAY 0.680851 (-485 2885);
PAINT MONO (-485 2885);
FORCEPROP 0 LASTPIN (-475 2925) $PN DU68
J 2
(-485 2935);
DISPLAY 0.680851 (-485 2935);
PAINT MONO (-485 2935);
FORCEPROP 0 LASTPIN (-475 2975) $PN DY69
J 2
(-485 2985);
DISPLAY 0.680851 (-485 2985);
PAINT MONO (-485 2985);
FORCEPROP 0 LASTPIN (-475 3025) $PN EA68
J 2
(-485 3035);
DISPLAY 0.680851 (-485 3035);
PAINT MONO (-485 3035);
FORCEPROP 0 LASTPIN (-475 3075) $PN DU66
J 2
(-485 3085);
DISPLAY 0.680851 (-485 3085);
PAINT MONO (-485 3085);
FORCEPROP 0 LASTPIN (-475 3125) $PN DV65
J 2
(-485 3135);
DISPLAY 0.680851 (-485 3135);
PAINT MONO (-485 3135);
FORCEPROP 0 LASTPIN (-475 3175) $PN EA66
J 2
(-485 3185);
DISPLAY 0.680851 (-485 3185);
PAINT MONO (-485 3185);
FORCEPROP 0 LASTPIN (-475 3225) $PN DY65
J 2
(-485 3235);
DISPLAY 0.680851 (-485 3235);
PAINT MONO (-485 3235);
FORCEPROP 0 LASTPIN (-475 3275) $PN EE66
J 2
(-485 3285);
DISPLAY 0.680851 (-485 3285);
PAINT MONO (-485 3285);
FORCEPROP 0 LASTPIN (-475 3325) $PN ED65
J 2
(-485 3335);
DISPLAY 0.680851 (-485 3335);
PAINT MONO (-485 3335);
FORCEPROP 0 LASTPIN (-475 3375) $PN EG66
J 2
(-485 3385);
DISPLAY 0.680851 (-485 3385);
PAINT MONO (-485 3385);
FORCEPROP 0 LASTPIN (-475 3425) $PN EH65
J 2
(-485 3435);
DISPLAY 0.680851 (-485 3435);
PAINT MONO (-485 3435);
FORCEPROP 0 LASTPIN (-475 3475) $PN ED63
J 2
(-485 3485);
DISPLAY 0.680851 (-485 3485);
PAINT MONO (-485 3485);
FORCEPROP 0 LASTPIN (-475 3525) $PN EE62
J 2
(-485 3535);
DISPLAY 0.680851 (-485 3535);
PAINT MONO (-485 3535);
FORCEPROP 0 LASTPIN (-475 3575) $PN EH63
J 2
(-485 3585);
DISPLAY 0.680851 (-485 3585);
PAINT MONO (-485 3585);
FORCEPROP 0 LASTPIN (-475 3625) $PN EG62
J 2
(-485 3635);
DISPLAY 0.680851 (-485 3635);
PAINT MONO (-485 3635);
FORCEPROP 0 LASTPIN (-475 3675) $PN DV57
J 2
(-485 3685);
DISPLAY 0.680851 (-485 3685);
PAINT MONO (-485 3685);
FORCEPROP 0 LASTPIN (-475 3725) $PN DU56
J 2
(-485 3735);
DISPLAY 0.680851 (-485 3735);
PAINT MONO (-485 3735);
FORCEPROP 0 LASTPIN (-475 3775) $PN DY57
J 2
(-485 3785);
DISPLAY 0.680851 (-485 3785);
PAINT MONO (-485 3785);
FORCEPROP 0 LASTPIN (-475 3825) $PN EA56
J 2
(-485 3835);
DISPLAY 0.680851 (-485 3835);
PAINT MONO (-485 3835);
FORCEPROP 0 LASTPIN (-475 3875) $PN DU54
J 2
(-485 3885);
DISPLAY 0.680851 (-485 3885);
PAINT MONO (-485 3885);
FORCEPROP 0 LASTPIN (-475 3925) $PN DV53
J 2
(-485 3935);
DISPLAY 0.680851 (-485 3935);
PAINT MONO (-485 3935);
FORCEPROP 0 LASTPIN (-475 3975) $PN EA54
J 2
(-485 3985);
DISPLAY 0.680851 (-485 3985);
PAINT MONO (-485 3985);
FORCEPROP 0 LASTPIN (-475 4025) $PN DY53
J 2
(-485 4035);
DISPLAY 0.680851 (-485 4035);
PAINT MONO (-485 4035);
FORCEPROP 0 LASTPIN (1975 3025) $PN EE76
J 0
(1985 3035);
DISPLAY 0.680851 (1985 3035);
PAINT MONO (1985 3035);
FORCEPROP 0 LASTPIN (1975 3075) $PN DT67
J 0
(1985 3085);
DISPLAY 0.680851 (1985 3085);
PAINT MONO (1985 3085);
FORCEPROP 0 LASTPIN (1975 3125) $PN EC64
J 0
(1985 3135);
DISPLAY 0.680851 (1985 3135);
PAINT MONO (1985 3135);
FORCEPROP 0 LASTPIN (1975 3175) $PN DV55
J 0
(1985 3185);
DISPLAY 0.680851 (1985 3185);
PAINT MONO (1985 3185);
FORCEPROP 0 LASTPIN (1975 3225) $PN EE58
J 0
(1985 3235);
DISPLAY 0.680851 (1985 3235);
PAINT MONO (1985 3235);
FORCEPROP 0 LASTPIN (1975 3275) $PN EJ76
J 0
(1985 3285);
DISPLAY 0.680851 (1985 3285);
PAINT MONO (1985 3285);
FORCEPROP 0 LASTPIN (1975 3325) $PN EB67
J 0
(1985 3335);
DISPLAY 0.680851 (1985 3335);
PAINT MONO (1985 3335);
FORCEPROP 0 LASTPIN (1975 3375) $PN EJ64
J 0
(1985 3385);
DISPLAY 0.680851 (1985 3385);
PAINT MONO (1985 3385);
FORCEPROP 0 LASTPIN (1975 3425) $PN EB55
J 0
(1985 3435);
DISPLAY 0.680851 (1985 3435);
PAINT MONO (1985 3435);
FORCEPROP 0 LASTPIN (1975 3475) $PN EJ58
J 0
(1985 3485);
DISPLAY 0.680851 (1985 3485);
PAINT MONO (1985 3485);
FORCEPROP 0 LASTPIN (1975 3575) $PN EC76
J 0
(1985 3585);
DISPLAY 0.680851 (1985 3585);
PAINT MONO (1985 3585);
FORCEPROP 0 LASTPIN (1975 3625) $PN DV67
J 0
(1985 3635);
DISPLAY 0.680851 (1985 3635);
PAINT MONO (1985 3635);
FORCEPROP 0 LASTPIN (1975 3675) $PN EE64
J 0
(1985 3685);
DISPLAY 0.680851 (1985 3685);
PAINT MONO (1985 3685);
FORCEPROP 0 LASTPIN (1975 3725) $PN DT55
J 0
(1985 3735);
DISPLAY 0.680851 (1985 3735);
PAINT MONO (1985 3735);
FORCEPROP 0 LASTPIN (1975 3775) $PN EC58
J 0
(1985 3785);
DISPLAY 0.680851 (1985 3785);
PAINT MONO (1985 3785);
FORCEPROP 0 LASTPIN (1975 3825) $PN EG76
J 0
(1985 3835);
DISPLAY 0.680851 (1985 3835);
PAINT MONO (1985 3835);
FORCEPROP 0 LASTPIN (1975 3875) $PN DY67
J 0
(1985 3885);
DISPLAY 0.680851 (1985 3885);
PAINT MONO (1985 3885);
FORCEPROP 0 LASTPIN (1975 3925) $PN EG64
J 0
(1985 3935);
DISPLAY 0.680851 (1985 3935);
PAINT MONO (1985 3935);
FORCEPROP 0 LASTPIN (1975 3975) $PN DY55
J 0
(1985 3985);
DISPLAY 0.680851 (1985 3985);
PAINT MONO (1985 3985);
FORCEPROP 0 LASTPIN (1975 4025) $PN EG58
J 0
(1985 4035);
DISPLAY 0.680851 (1985 4035);
PAINT MONO (1985 4035);
FORCEPROP 0 LASTPIN (-475 2075) $PN EE60
J 2
(-485 2085);
DISPLAY 0.680851 (-485 2085);
PAINT MONO (-485 2085);
FORCEPROP 0 LASTPIN (-475 2125) $PN ED59
J 2
(-485 2135);
DISPLAY 0.680851 (-485 2135);
PAINT MONO (-485 2135);
FORCEPROP 0 LASTPIN (-475 2175) $PN EG60
J 2
(-485 2185);
DISPLAY 0.680851 (-485 2185);
PAINT MONO (-485 2185);
FORCEPROP 0 LASTPIN (-475 2225) $PN EH59
J 2
(-485 2235);
DISPLAY 0.680851 (-485 2235);
PAINT MONO (-485 2235);
FORCEPROP 0 LASTPIN (-475 2275) $PN ED57
J 2
(-485 2285);
DISPLAY 0.680851 (-485 2285);
PAINT MONO (-485 2285);
FORCEPROP 0 LASTPIN (-475 2325) $PN EE56
J 2
(-485 2335);
DISPLAY 0.680851 (-485 2335);
PAINT MONO (-485 2335);
FORCEPROP 0 LASTPIN (-475 2375) $PN EH57
J 2
(-485 2385);
DISPLAY 0.680851 (-485 2385);
PAINT MONO (-485 2385);
FORCEPROP 0 LASTPIN (-475 2425) $PN EG56
J 2
(-485 2435);
DISPLAY 0.680851 (-485 2435);
PAINT MONO (-485 2435);
FORCEPROP 0 LASTPIN (1975 1375) $PN EA50
J 0
(1985 1385);
DISPLAY 0.680851 (1985 1385);
PAINT MONO (1985 1385);
FORCEPROP 0 LASTPIN (1975 925) $PN DV51
J 0
(1985 935);
DISPLAY 0.680851 (1985 935);
PAINT MONO (1985 935);
FORCEPROP 0 LASTPIN (1975 975) $PN DU50
J 0
(1985 985);
DISPLAY 0.680851 (1985 985);
PAINT MONO (1985 985);
FORCEPROP 0 LASTPIN (1975 1025) $PN EE41
J 0
(1985 1035);
DISPLAY 0.680851 (1985 1035);
PAINT MONO (1985 1035);
FORCEPROP 0 LASTPIN (1975 1075) $PN EG41
J 0
(1985 1085);
DISPLAY 0.680851 (1985 1085);
PAINT MONO (1985 1085);
FORCEPROP 0 LASTPIN (1975 1125) $PN ED40
J 0
(1985 1135);
DISPLAY 0.680851 (1985 1135);
PAINT MONO (1985 1135);
FORCEPROP 0 LASTPIN (1975 1175) $PN EH40
J 0
(1985 1185);
DISPLAY 0.680851 (1985 1185);
PAINT MONO (1985 1185);
FORCEPROP 0 LASTPIN (1975 1225) $PN EC39
J 0
(1985 1235);
DISPLAY 0.680851 (1985 1235);
PAINT MONO (1985 1235);
FORCEPROP 0 LASTPIN (-475 475) $PN DV32
J 2
(-485 485);
DISPLAY 0.680851 (-485 485);
PAINT MONO (-485 485);
FORCEPROP 0 LASTPIN (-475 525) $PN DU31
J 2
(-485 535);
DISPLAY 0.680851 (-485 535);
PAINT MONO (-485 535);
FORCEPROP 0 LASTPIN (-475 575) $PN DY32
J 2
(-485 585);
DISPLAY 0.680851 (-485 585);
PAINT MONO (-485 585);
FORCEPROP 0 LASTPIN (-475 625) $PN EA31
J 2
(-485 635);
DISPLAY 0.680851 (-485 635);
PAINT MONO (-485 635);
FORCEPROP 0 LASTPIN (-475 675) $PN DU29
J 2
(-485 685);
DISPLAY 0.680851 (-485 685);
PAINT MONO (-485 685);
FORCEPROP 0 LASTPIN (-475 725) $PN DV28
J 2
(-485 735);
DISPLAY 0.680851 (-485 735);
PAINT MONO (-485 735);
FORCEPROP 0 LASTPIN (-475 775) $PN EA29
J 2
(-485 785);
DISPLAY 0.680851 (-485 785);
PAINT MONO (-485 785);
FORCEPROP 0 LASTPIN (-475 825) $PN DY28
J 2
(-485 835);
DISPLAY 0.680851 (-485 835);
PAINT MONO (-485 835);
FORCEPROP 0 LASTPIN (-475 875) $PN EE23
J 2
(-485 885);
DISPLAY 0.680851 (-485 885);
PAINT MONO (-485 885);
FORCEPROP 0 LASTPIN (-475 925) $PN ED22
J 2
(-485 935);
DISPLAY 0.680851 (-485 935);
PAINT MONO (-485 935);
FORCEPROP 0 LASTPIN (-475 975) $PN EG23
J 2
(-485 985);
DISPLAY 0.680851 (-485 985);
PAINT MONO (-485 985);
FORCEPROP 0 LASTPIN (-475 1025) $PN EH22
J 2
(-485 1035);
DISPLAY 0.680851 (-485 1035);
PAINT MONO (-485 1035);
FORCEPROP 0 LASTPIN (-475 1075) $PN ED20
J 2
(-485 1085);
DISPLAY 0.680851 (-485 1085);
PAINT MONO (-485 1085);
FORCEPROP 0 LASTPIN (-475 1125) $PN EE19
J 2
(-485 1135);
DISPLAY 0.680851 (-485 1135);
PAINT MONO (-485 1135);
FORCEPROP 0 LASTPIN (-475 1175) $PN EH20
J 2
(-485 1185);
DISPLAY 0.680851 (-485 1185);
PAINT MONO (-485 1185);
FORCEPROP 0 LASTPIN (-475 1225) $PN EG19
J 2
(-485 1235);
DISPLAY 0.680851 (-485 1235);
PAINT MONO (-485 1235);
FORCEPROP 0 LASTPIN (-475 1275) $PN EM14
J 2
(-485 1285);
DISPLAY 0.680851 (-485 1285);
PAINT MONO (-485 1285);
FORCEPROP 0 LASTPIN (-475 1325) $PN EL13
J 2
(-485 1335);
DISPLAY 0.680851 (-485 1335);
PAINT MONO (-485 1335);
FORCEPROP 0 LASTPIN (-475 1375) $PN EP14
J 2
(-485 1385);
DISPLAY 0.680851 (-485 1385);
PAINT MONO (-485 1385);
FORCEPROP 0 LASTPIN (-475 1425) $PN ER13
J 2
(-485 1435);
DISPLAY 0.680851 (-485 1435);
PAINT MONO (-485 1435);
FORCEPROP 0 LASTPIN (-475 1475) $PN EL11
J 2
(-485 1485);
DISPLAY 0.680851 (-485 1485);
PAINT MONO (-485 1485);
FORCEPROP 0 LASTPIN (-475 1525) $PN EM10
J 2
(-485 1535);
DISPLAY 0.680851 (-485 1535);
PAINT MONO (-485 1535);
FORCEPROP 0 LASTPIN (-475 1575) $PN ER11
J 2
(-485 1585);
DISPLAY 0.680851 (-485 1585);
PAINT MONO (-485 1585);
FORCEPROP 0 LASTPIN (-475 1625) $PN EP10
J 2
(-485 1635);
DISPLAY 0.680851 (-485 1635);
PAINT MONO (-485 1635);
FORCEPROP 0 LASTPIN (-475 1675) $PN DV20
J 2
(-485 1685);
DISPLAY 0.680851 (-485 1685);
PAINT MONO (-485 1685);
FORCEPROP 0 LASTPIN (-475 1725) $PN DU19
J 2
(-485 1735);
DISPLAY 0.680851 (-485 1735);
PAINT MONO (-485 1735);
FORCEPROP 0 LASTPIN (-475 1775) $PN DY20
J 2
(-485 1785);
DISPLAY 0.680851 (-485 1785);
PAINT MONO (-485 1785);
FORCEPROP 0 LASTPIN (-475 1825) $PN EA19
J 2
(-485 1835);
DISPLAY 0.680851 (-485 1835);
PAINT MONO (-485 1835);
FORCEPROP 0 LASTPIN (-475 1875) $PN EA17
J 2
(-485 1885);
DISPLAY 0.680851 (-485 1885);
PAINT MONO (-485 1885);
FORCEPROP 0 LASTPIN (-475 1925) $PN DU17
J 2
(-485 1935);
DISPLAY 0.680851 (-485 1935);
PAINT MONO (-485 1935);
FORCEPROP 0 LASTPIN (-475 1975) $PN EC17
J 2
(-485 1985);
DISPLAY 0.680851 (-485 1985);
PAINT MONO (-485 1985);
FORCEPROP 0 LASTPIN (-475 2025) $PN DR17
J 2
(-485 2035);
DISPLAY 0.680851 (-485 2035);
PAINT MONO (-485 2035);
FORCEPROP 0 LASTPIN (1975 1875) $PN DV30
J 0
(1985 1885);
DISPLAY 0.680851 (1985 1885);
PAINT MONO (1985 1885);
FORCEPROP 0 LASTPIN (1975 1925) $PN EE21
J 0
(1985 1935);
DISPLAY 0.680851 (1985 1935);
PAINT MONO (1985 1935);
FORCEPROP 0 LASTPIN (1975 1975) $PN EM12
J 0
(1985 1985);
DISPLAY 0.680851 (1985 1985);
PAINT MONO (1985 1985);
FORCEPROP 0 LASTPIN (1975 2025) $PN DT18
J 0
(1985 2035);
DISPLAY 0.680851 (1985 2035);
PAINT MONO (1985 2035);
FORCEPROP 0 LASTPIN (1975 2075) $PN EJ33
J 0
(1985 2085);
DISPLAY 0.680851 (1985 2085);
PAINT MONO (1985 2085);
FORCEPROP 0 LASTPIN (1975 2125) $PN EB30
J 0
(1985 2135);
DISPLAY 0.680851 (1985 2135);
PAINT MONO (1985 2135);
FORCEPROP 0 LASTPIN (1975 2175) $PN EJ21
J 0
(1985 2185);
DISPLAY 0.680851 (1985 2185);
PAINT MONO (1985 2185);
FORCEPROP 0 LASTPIN (1975 2225) $PN ET12
J 0
(1985 2235);
DISPLAY 0.680851 (1985 2235);
PAINT MONO (1985 2235);
FORCEPROP 0 LASTPIN (1975 2275) $PN DY18
J 0
(1985 2285);
DISPLAY 0.680851 (1985 2285);
PAINT MONO (1985 2285);
FORCEPROP 0 LASTPIN (1975 2325) $PN EE33
J 0
(1985 2335);
DISPLAY 0.680851 (1985 2335);
PAINT MONO (1985 2335);
FORCEPROP 0 LASTPIN (1975 2425) $PN DT30
J 0
(1985 2435);
DISPLAY 0.680851 (1985 2435);
PAINT MONO (1985 2435);
FORCEPROP 0 LASTPIN (1975 2475) $PN EC21
J 0
(1985 2485);
DISPLAY 0.680851 (1985 2485);
PAINT MONO (1985 2485);
FORCEPROP 0 LASTPIN (1975 2525) $PN EK12
J 0
(1985 2535);
DISPLAY 0.680851 (1985 2535);
PAINT MONO (1985 2535);
FORCEPROP 0 LASTPIN (1975 2575) $PN DV18
J 0
(1985 2585);
DISPLAY 0.680851 (1985 2585);
PAINT MONO (1985 2585);
FORCEPROP 0 LASTPIN (1975 2625) $PN EG33
J 0
(1985 2635);
DISPLAY 0.680851 (1985 2635);
PAINT MONO (1985 2635);
FORCEPROP 0 LASTPIN (1975 2675) $PN DY30
J 0
(1985 2685);
DISPLAY 0.680851 (1985 2685);
PAINT MONO (1985 2685);
FORCEPROP 0 LASTPIN (1975 2725) $PN EG21
J 0
(1985 2735);
DISPLAY 0.680851 (1985 2735);
PAINT MONO (1985 2735);
FORCEPROP 0 LASTPIN (1975 2775) $PN EP12
J 0
(1985 2785);
DISPLAY 0.680851 (1985 2785);
PAINT MONO (1985 2785);
FORCEPROP 0 LASTPIN (1975 2825) $PN EB18
J 0
(1985 2835);
DISPLAY 0.680851 (1985 2835);
PAINT MONO (1985 2835);
FORCEPROP 0 LASTPIN (1975 2875) $PN EC33
J 0
(1985 2885);
DISPLAY 0.680851 (1985 2885);
PAINT MONO (1985 2885);
FORCEPROP 0 LASTPIN (-475 75) $PN ED32
J 2
(-485 85);
DISPLAY 0.680851 (-485 85);
PAINT MONO (-485 85);
FORCEPROP 0 LASTPIN (-475 125) $PN EE31
J 2
(-485 135);
DISPLAY 0.680851 (-485 135);
PAINT MONO (-485 135);
FORCEPROP 0 LASTPIN (-475 175) $PN EH32
J 2
(-485 185);
DISPLAY 0.680851 (-485 185);
PAINT MONO (-485 185);
FORCEPROP 0 LASTPIN (-475 225) $PN EG31
J 2
(-485 235);
DISPLAY 0.680851 (-485 235);
PAINT MONO (-485 235);
FORCEPROP 0 LASTPIN (-475 275) $PN EE35
J 2
(-485 285);
DISPLAY 0.680851 (-485 285);
PAINT MONO (-485 285);
FORCEPROP 0 LASTPIN (-475 325) $PN ED34
J 2
(-485 335);
DISPLAY 0.680851 (-485 335);
PAINT MONO (-485 335);
FORCEPROP 0 LASTPIN (-475 375) $PN EG35
J 2
(-485 385);
DISPLAY 0.680851 (-485 385);
PAINT MONO (-485 385);
FORCEPROP 0 LASTPIN (-475 425) $PN EH34
J 2
(-485 435);
DISPLAY 0.680851 (-485 435);
PAINT MONO (-485 435);
FORCEPROP 0 LASTPIN (1975 875) $PN EJ39
J 0
(1985 885);
DISPLAY 0.680851 (1985 885);
PAINT MONO (1985 885);
FORCEPROP 0 LASTPIN (1975 575) $PN EG54
J 0
(1985 585);
DISPLAY 0.680851 (1985 585);
PAINT MONO (1985 585);
FORCEPROP 0 LASTPIN (1975 625) $PN EH53
J 0
(1985 635);
DISPLAY 0.680851 (1985 635);
PAINT MONO (1985 635);
FORCEPROP 0 LASTPIN (1975 675) $PN EE54
J 0
(1985 685);
DISPLAY 0.680851 (1985 685);
PAINT MONO (1985 685);
FORCEPROP 0 LASTPIN (1975 725) $PN ED53
J 0
(1985 735);
DISPLAY 0.680851 (1985 735);
PAINT MONO (1985 735);
FORCEPROP 0 LASTPIN (1975 275) $PN EH38
J 0
(1985 285);
DISPLAY 0.680851 (1985 285);
PAINT MONO (1985 285);
FORCEPROP 0 LASTPIN (1975 325) $PN EG37
J 0
(1985 335);
DISPLAY 0.680851 (1985 335);
PAINT MONO (1985 335);
FORCEPROP 0 LASTPIN (1975 375) $PN ED38
J 0
(1985 385);
DISPLAY 0.680851 (1985 385);
PAINT MONO (1985 385);
FORCEPROP 0 LASTPIN (1975 425) $PN EE37
J 0
(1985 435);
DISPLAY 0.680851 (1985 435);
PAINT MONO (1985 435);
FORCEPROP 2 LAST CDS_LIB pure_quanta
J 0
(750 1925);
DISPLAY INVISIBLE (750 1925);
FORCEPROP 1 LAST NEEDS_NO_SIZE TRUE
J 0
(750 1925);
DISPLAY 0.723404 (750 1925);
PAINT GREEN (750 1925);
DISPLAY INVISIBLE (750 1925);
FORCEPROP 1 LAST CDS_LMAN_SYM_OUTLINE -1100,2250,1050,-2250
J 0
(750 1925);
DISPLAY 0.468085 (750 1925);
PAINT GREEN (750 1925);
DISPLAY INVISIBLE (750 1925);
FORCEPROP 2 LAST CDS_LOCATION U1
J 0
(-350 4500);
DISPLAY 1.021277 (-350 4500);
DISPLAY INVISIBLE (-350 4500);
FORCEPROP 0 LAST $SEC 13
J 0
(-350 4500);
DISPLAY 0.680851 (-350 4500);
PAINT MONO (-350 4500);
DISPLAY INVISIBLE (-350 4500);
FORCEPROP 2 LAST CDS_SEC 13
J 0
(-350 4500);
DISPLAY 1.021277 (-350 4500);
DISPLAY INVISIBLE (-350 4500);
FORCEPROP 1 LAST PATH I168
J 0
(750 1925);
DISPLAY 0.723404 (750 1925);
PAINT GREEN (750 1925);
DISPLAY INVISIBLE (750 1925);
FORCEADD TAP..1
R 2
(-975 425);
FORCEPROP 3 LASTPIN (-925 425) SIG_NAME M_F_CPU1_SB_CB<7>
J 0
(-915 435);
DISPLAY 0.659574 (-915 435);
PAINT MONO (-915 435);
DISPLAY INVISIBLE (-915 435);
FORCEPROP 1 LASTPIN (-925 425) BN 7
J 2
(-913 433);
DISPLAY 0.680851 (-913 433);
PAINT GREEN (-913 433);
FORCEPROP 2 LAST CDS_LIB standard
J 0
(-975 425);
DISPLAY INVISIBLE (-975 425);
FORCEPROP 1 LAST BODY_TYPE PLUMBING
J 2
(-975 475);
DISPLAY 0.872340 (-975 475);
PAINT GREEN (-975 475);
DISPLAY INVISIBLE (-975 475);
FORCEPROP 1 LAST HDL_TAP TRUE
J 2
(-1300 300);
DISPLAY 0.872340 (-1300 300);
DISPLAY INVISIBLE (-1300 300);
FORCEPROP 1 LAST PATH I17
J 2
(-973 425);
DISPLAY 0.872340 (-973 425);
PAINT GREEN (-973 425);
DISPLAY INVISIBLE (-973 425);
FORCEADD TAP..1
R 2
(-975 525);
FORCEPROP 3 LASTPIN (-925 525) SIG_NAME M_F_CPU1_SB_DQ<1>
J 0
(-915 535);
DISPLAY 0.659574 (-915 535);
PAINT MONO (-915 535);
DISPLAY INVISIBLE (-915 535);
FORCEPROP 1 LASTPIN (-925 525) BN 1
J 2
(-913 533);
DISPLAY 0.680851 (-913 533);
PAINT GREEN (-913 533);
FORCEPROP 2 LAST CDS_LIB standard
J 0
(-975 525);
DISPLAY INVISIBLE (-975 525);
FORCEPROP 1 LAST BODY_TYPE PLUMBING
J 2
(-975 575);
DISPLAY 0.872340 (-975 575);
PAINT GREEN (-975 575);
DISPLAY INVISIBLE (-975 575);
FORCEPROP 1 LAST HDL_TAP TRUE
J 2
(-1300 400);
DISPLAY 0.872340 (-1300 400);
DISPLAY INVISIBLE (-1300 400);
FORCEPROP 1 LAST PATH I18
J 2
(-973 525);
DISPLAY 0.872340 (-973 525);
PAINT GREEN (-973 525);
DISPLAY INVISIBLE (-973 525);
FORCEADD TAP..1
R 2
(-975 625);
FORCEPROP 3 LASTPIN (-925 625) SIG_NAME M_F_CPU1_SB_DQ<3>
J 0
(-915 635);
DISPLAY 0.659574 (-915 635);
PAINT MONO (-915 635);
DISPLAY INVISIBLE (-915 635);
FORCEPROP 1 LASTPIN (-925 625) BN 3
J 2
(-913 633);
DISPLAY 0.680851 (-913 633);
PAINT GREEN (-913 633);
FORCEPROP 2 LAST CDS_LIB standard
J 0
(-975 625);
DISPLAY INVISIBLE (-975 625);
FORCEPROP 1 LAST BODY_TYPE PLUMBING
J 2
(-975 675);
DISPLAY 0.872340 (-975 675);
PAINT GREEN (-975 675);
DISPLAY INVISIBLE (-975 675);
FORCEPROP 1 LAST HDL_TAP TRUE
J 2
(-1300 500);
DISPLAY 0.872340 (-1300 500);
DISPLAY INVISIBLE (-1300 500);
FORCEPROP 1 LAST PATH I19
J 2
(-973 625);
DISPLAY 0.872340 (-973 625);
PAINT GREEN (-973 625);
DISPLAY INVISIBLE (-973 625);
FORCEADD OFFPAGE..2
R 2
(-2000 -100);
FORCEPROP 2 LAST $XR1 109 
J 0
(-2375 -100);
DISPLAY 0.638298 (-2375 -100);
PAINT MONO (-2375 -100);
FORCEPROP 2 LAST $XR0 108 
J 0
(-2255 -100);
DISPLAY 0.638298 (-2255 -100);
PAINT MONO (-2255 -100);
FORCEPROP 2 LAST CDS_LIB standard
J 0
(-2000 -100);
PAINT MONO (-2000 -100);
DISPLAY INVISIBLE (-2000 -100);
FORCEPROP 1 LAST OFFPAGE TRUE
J 2
(-2325 -225);
DISPLAY 0.872340 (-2325 -225);
DISPLAY INVISIBLE (-2325 -225);
FORCEPROP 1 LAST COMMENT_BODY TRUE
J 2
(-1955 -195);
DISPLAY 0.872340 (-1955 -195);
PAINT GREEN (-1955 -195);
DISPLAY INVISIBLE (-1955 -195);
FORCEPROP 2 LAST PATH I2
J 0
(-1950 -25);
DISPLAY 1.021277 (-1950 -25);
DISPLAY INVISIBLE (-1950 -25);
FORCEADD TAP..1
R 2
(-975 575);
FORCEPROP 3 LASTPIN (-925 575) SIG_NAME M_F_CPU1_SB_DQ<2>
J 0
(-915 585);
DISPLAY 0.659574 (-915 585);
PAINT MONO (-915 585);
DISPLAY INVISIBLE (-915 585);
FORCEPROP 1 LASTPIN (-925 575) BN 2
J 2
(-913 583);
DISPLAY 0.680851 (-913 583);
PAINT GREEN (-913 583);
FORCEPROP 2 LAST CDS_LIB standard
J 0
(-975 575);
DISPLAY INVISIBLE (-975 575);
FORCEPROP 1 LAST BODY_TYPE PLUMBING
J 2
(-975 625);
DISPLAY 0.872340 (-975 625);
PAINT GREEN (-975 625);
DISPLAY INVISIBLE (-975 625);
FORCEPROP 1 LAST HDL_TAP TRUE
J 2
(-1300 450);
DISPLAY 0.872340 (-1300 450);
DISPLAY INVISIBLE (-1300 450);
FORCEPROP 1 LAST PATH I20
J 2
(-973 575);
DISPLAY 0.872340 (-973 575);
PAINT GREEN (-973 575);
DISPLAY INVISIBLE (-973 575);
FORCEADD TAP..1
R 2
(-975 675);
FORCEPROP 3 LASTPIN (-925 675) SIG_NAME M_F_CPU1_SB_DQ<4>
J 0
(-915 685);
DISPLAY 0.659574 (-915 685);
PAINT MONO (-915 685);
DISPLAY INVISIBLE (-915 685);
FORCEPROP 1 LASTPIN (-925 675) BN 4
J 2
(-913 683);
DISPLAY 0.680851 (-913 683);
PAINT GREEN (-913 683);
FORCEPROP 2 LAST CDS_LIB standard
J 0
(-975 675);
DISPLAY INVISIBLE (-975 675);
FORCEPROP 1 LAST BODY_TYPE PLUMBING
J 2
(-975 725);
DISPLAY 0.872340 (-975 725);
PAINT GREEN (-975 725);
DISPLAY INVISIBLE (-975 725);
FORCEPROP 1 LAST HDL_TAP TRUE
J 2
(-1300 550);
DISPLAY 0.872340 (-1300 550);
DISPLAY INVISIBLE (-1300 550);
FORCEPROP 1 LAST PATH I21
J 2
(-973 675);
DISPLAY 0.872340 (-973 675);
PAINT GREEN (-973 675);
DISPLAY INVISIBLE (-973 675);
FORCEADD TAP..1
R 2
(-975 775);
FORCEPROP 3 LASTPIN (-925 775) SIG_NAME M_F_CPU1_SB_DQ<6>
J 0
(-915 785);
DISPLAY 0.659574 (-915 785);
PAINT MONO (-915 785);
DISPLAY INVISIBLE (-915 785);
FORCEPROP 1 LASTPIN (-925 775) BN 6
J 2
(-913 783);
DISPLAY 0.680851 (-913 783);
PAINT GREEN (-913 783);
FORCEPROP 2 LAST CDS_LIB standard
J 0
(-975 775);
DISPLAY INVISIBLE (-975 775);
FORCEPROP 1 LAST BODY_TYPE PLUMBING
J 2
(-975 825);
DISPLAY 0.872340 (-975 825);
PAINT GREEN (-975 825);
DISPLAY INVISIBLE (-975 825);
FORCEPROP 1 LAST HDL_TAP TRUE
J 2
(-1300 650);
DISPLAY 0.872340 (-1300 650);
DISPLAY INVISIBLE (-1300 650);
FORCEPROP 1 LAST PATH I22
J 2
(-973 775);
DISPLAY 0.872340 (-973 775);
PAINT GREEN (-973 775);
DISPLAY INVISIBLE (-973 775);
FORCEADD TAP..1
R 2
(-975 725);
FORCEPROP 3 LASTPIN (-925 725) SIG_NAME M_F_CPU1_SB_DQ<5>
J 0
(-915 735);
DISPLAY 0.659574 (-915 735);
PAINT MONO (-915 735);
DISPLAY INVISIBLE (-915 735);
FORCEPROP 1 LASTPIN (-925 725) BN 5
J 2
(-913 733);
DISPLAY 0.680851 (-913 733);
PAINT GREEN (-913 733);
FORCEPROP 2 LAST CDS_LIB standard
J 0
(-975 725);
DISPLAY INVISIBLE (-975 725);
FORCEPROP 1 LAST BODY_TYPE PLUMBING
J 2
(-975 775);
DISPLAY 0.872340 (-975 775);
PAINT GREEN (-975 775);
DISPLAY INVISIBLE (-975 775);
FORCEPROP 1 LAST HDL_TAP TRUE
J 2
(-1300 600);
DISPLAY 0.872340 (-1300 600);
DISPLAY INVISIBLE (-1300 600);
FORCEPROP 1 LAST PATH I23
J 2
(-973 725);
DISPLAY 0.872340 (-973 725);
PAINT GREEN (-973 725);
DISPLAY INVISIBLE (-973 725);
FORCEADD TAP..1
R 2
(-975 875);
FORCEPROP 3 LASTPIN (-925 875) SIG_NAME M_F_CPU1_SB_DQ<8>
J 0
(-915 885);
DISPLAY 0.659574 (-915 885);
PAINT MONO (-915 885);
DISPLAY INVISIBLE (-915 885);
FORCEPROP 1 LASTPIN (-925 875) BN 8
J 2
(-913 883);
DISPLAY 0.680851 (-913 883);
PAINT GREEN (-913 883);
FORCEPROP 2 LAST CDS_LIB standard
J 0
(-975 875);
DISPLAY INVISIBLE (-975 875);
FORCEPROP 1 LAST BODY_TYPE PLUMBING
J 2
(-975 925);
DISPLAY 0.872340 (-975 925);
PAINT GREEN (-975 925);
DISPLAY INVISIBLE (-975 925);
FORCEPROP 1 LAST HDL_TAP TRUE
J 2
(-1300 750);
DISPLAY 0.872340 (-1300 750);
DISPLAY INVISIBLE (-1300 750);
FORCEPROP 1 LAST PATH I24
J 2
(-973 875);
DISPLAY 0.872340 (-973 875);
PAINT GREEN (-973 875);
DISPLAY INVISIBLE (-973 875);
FORCEADD TAP..1
R 2
(-975 825);
FORCEPROP 3 LASTPIN (-925 825) SIG_NAME M_F_CPU1_SB_DQ<7>
J 0
(-915 835);
DISPLAY 0.659574 (-915 835);
PAINT MONO (-915 835);
DISPLAY INVISIBLE (-915 835);
FORCEPROP 1 LASTPIN (-925 825) BN 7
J 2
(-913 833);
DISPLAY 0.680851 (-913 833);
PAINT GREEN (-913 833);
FORCEPROP 2 LAST CDS_LIB standard
J 0
(-975 825);
DISPLAY INVISIBLE (-975 825);
FORCEPROP 1 LAST BODY_TYPE PLUMBING
J 2
(-975 875);
DISPLAY 0.872340 (-975 875);
PAINT GREEN (-975 875);
DISPLAY INVISIBLE (-975 875);
FORCEPROP 1 LAST HDL_TAP TRUE
J 2
(-1300 700);
DISPLAY 0.872340 (-1300 700);
DISPLAY INVISIBLE (-1300 700);
FORCEPROP 1 LAST PATH I25
J 2
(-973 825);
DISPLAY 0.872340 (-973 825);
PAINT GREEN (-973 825);
DISPLAY INVISIBLE (-973 825);
FORCEADD TAP..1
R 2
(-975 925);
FORCEPROP 3 LASTPIN (-925 925) SIG_NAME M_F_CPU1_SB_DQ<9>
J 0
(-915 935);
DISPLAY 0.659574 (-915 935);
PAINT MONO (-915 935);
DISPLAY INVISIBLE (-915 935);
FORCEPROP 1 LASTPIN (-925 925) BN 9
J 2
(-913 933);
DISPLAY 0.680851 (-913 933);
PAINT GREEN (-913 933);
FORCEPROP 2 LAST CDS_LIB standard
J 0
(-975 925);
DISPLAY INVISIBLE (-975 925);
FORCEPROP 1 LAST BODY_TYPE PLUMBING
J 2
(-975 975);
DISPLAY 0.872340 (-975 975);
PAINT GREEN (-975 975);
DISPLAY INVISIBLE (-975 975);
FORCEPROP 1 LAST HDL_TAP TRUE
J 2
(-1300 800);
DISPLAY 0.872340 (-1300 800);
DISPLAY INVISIBLE (-1300 800);
FORCEPROP 1 LAST PATH I26
J 2
(-973 925);
DISPLAY 0.872340 (-973 925);
PAINT GREEN (-973 925);
DISPLAY INVISIBLE (-973 925);
FORCEADD TAP..1
R 2
(-975 975);
FORCEPROP 3 LASTPIN (-925 975) SIG_NAME M_F_CPU1_SB_DQ<10>
J 0
(-915 985);
DISPLAY 0.659574 (-915 985);
PAINT MONO (-915 985);
DISPLAY INVISIBLE (-915 985);
FORCEPROP 1 LASTPIN (-925 975) BN 10
J 2
(-913 983);
DISPLAY 0.680851 (-913 983);
PAINT GREEN (-913 983);
FORCEPROP 2 LAST CDS_LIB standard
J 0
(-975 975);
DISPLAY INVISIBLE (-975 975);
FORCEPROP 1 LAST BODY_TYPE PLUMBING
J 2
(-975 1025);
DISPLAY 0.872340 (-975 1025);
PAINT GREEN (-975 1025);
DISPLAY INVISIBLE (-975 1025);
FORCEPROP 1 LAST HDL_TAP TRUE
J 2
(-1300 850);
DISPLAY 0.872340 (-1300 850);
DISPLAY INVISIBLE (-1300 850);
FORCEPROP 1 LAST PATH I27
J 2
(-973 975);
DISPLAY 0.872340 (-973 975);
PAINT GREEN (-973 975);
DISPLAY INVISIBLE (-973 975);
FORCEADD TAP..1
R 2
(-975 1025);
FORCEPROP 3 LASTPIN (-925 1025) SIG_NAME M_F_CPU1_SB_DQ<11>
J 0
(-915 1035);
DISPLAY 0.659574 (-915 1035);
PAINT MONO (-915 1035);
DISPLAY INVISIBLE (-915 1035);
FORCEPROP 1 LASTPIN (-925 1025) BN 11
J 2
(-913 1033);
DISPLAY 0.680851 (-913 1033);
PAINT GREEN (-913 1033);
FORCEPROP 2 LAST CDS_LIB standard
J 0
(-975 1025);
DISPLAY INVISIBLE (-975 1025);
FORCEPROP 1 LAST BODY_TYPE PLUMBING
J 2
(-975 1075);
DISPLAY 0.872340 (-975 1075);
PAINT GREEN (-975 1075);
DISPLAY INVISIBLE (-975 1075);
FORCEPROP 1 LAST HDL_TAP TRUE
J 2
(-1300 900);
DISPLAY 0.872340 (-1300 900);
DISPLAY INVISIBLE (-1300 900);
FORCEPROP 1 LAST PATH I28
J 2
(-973 1025);
DISPLAY 0.872340 (-973 1025);
PAINT GREEN (-973 1025);
DISPLAY INVISIBLE (-973 1025);
FORCEADD TAP..1
R 2
(-975 1125);
FORCEPROP 3 LASTPIN (-925 1125) SIG_NAME M_F_CPU1_SB_DQ<13>
J 0
(-915 1135);
DISPLAY 0.659574 (-915 1135);
PAINT MONO (-915 1135);
DISPLAY INVISIBLE (-915 1135);
FORCEPROP 1 LASTPIN (-925 1125) BN 13
J 2
(-913 1133);
DISPLAY 0.680851 (-913 1133);
PAINT GREEN (-913 1133);
FORCEPROP 2 LAST CDS_LIB standard
J 0
(-975 1125);
DISPLAY INVISIBLE (-975 1125);
FORCEPROP 1 LAST BODY_TYPE PLUMBING
J 2
(-975 1175);
DISPLAY 0.872340 (-975 1175);
PAINT GREEN (-975 1175);
DISPLAY INVISIBLE (-975 1175);
FORCEPROP 1 LAST HDL_TAP TRUE
J 2
(-1300 1000);
DISPLAY 0.872340 (-1300 1000);
DISPLAY INVISIBLE (-1300 1000);
FORCEPROP 1 LAST PATH I29
J 2
(-973 1125);
DISPLAY 0.872340 (-973 1125);
PAINT GREEN (-973 1125);
DISPLAY INVISIBLE (-973 1125);
FORCEADD TAP..1
R 2
(-975 -125);
FORCEPROP 3 LASTPIN (-925 -125) SIG_NAME M_F_CPU1_CLK_DN<1>
J 0
(-915 -115);
DISPLAY 0.659574 (-915 -115);
PAINT MONO (-915 -115);
DISPLAY INVISIBLE (-915 -115);
FORCEPROP 1 LASTPIN (-925 -125) BN 1
J 2
(-913 -117);
DISPLAY 0.680851 (-913 -117);
PAINT GREEN (-913 -117);
FORCEPROP 2 LAST CDS_LIB standard
J 0
(-975 -125);
DISPLAY INVISIBLE (-975 -125);
FORCEPROP 1 LAST BODY_TYPE PLUMBING
J 2
(-975 -75);
DISPLAY 0.872340 (-975 -75);
PAINT GREEN (-975 -75);
DISPLAY INVISIBLE (-975 -75);
FORCEPROP 1 LAST HDL_TAP TRUE
J 2
(-1300 -250);
DISPLAY 0.872340 (-1300 -250);
DISPLAY INVISIBLE (-1300 -250);
FORCEPROP 1 LAST PATH I3
J 2
(-973 -125);
DISPLAY 0.872340 (-973 -125);
PAINT GREEN (-973 -125);
DISPLAY INVISIBLE (-973 -125);
FORCEADD TAP..1
R 2
(-975 1075);
FORCEPROP 3 LASTPIN (-925 1075) SIG_NAME M_F_CPU1_SB_DQ<12>
J 0
(-915 1085);
DISPLAY 0.659574 (-915 1085);
PAINT MONO (-915 1085);
DISPLAY INVISIBLE (-915 1085);
FORCEPROP 1 LASTPIN (-925 1075) BN 12
J 2
(-913 1083);
DISPLAY 0.680851 (-913 1083);
PAINT GREEN (-913 1083);
FORCEPROP 2 LAST CDS_LIB standard
J 0
(-975 1075);
DISPLAY INVISIBLE (-975 1075);
FORCEPROP 1 LAST BODY_TYPE PLUMBING
J 2
(-975 1125);
DISPLAY 0.872340 (-975 1125);
PAINT GREEN (-975 1125);
DISPLAY INVISIBLE (-975 1125);
FORCEPROP 1 LAST HDL_TAP TRUE
J 2
(-1300 950);
DISPLAY 0.872340 (-1300 950);
DISPLAY INVISIBLE (-1300 950);
FORCEPROP 1 LAST PATH I30
J 2
(-973 1075);
DISPLAY 0.872340 (-973 1075);
PAINT GREEN (-973 1075);
DISPLAY INVISIBLE (-973 1075);
FORCEADD TAP..1
R 2
(-975 1175);
FORCEPROP 3 LASTPIN (-925 1175) SIG_NAME M_F_CPU1_SB_DQ<14>
J 0
(-915 1185);
DISPLAY 0.659574 (-915 1185);
PAINT MONO (-915 1185);
DISPLAY INVISIBLE (-915 1185);
FORCEPROP 1 LASTPIN (-925 1175) BN 14
J 2
(-913 1183);
DISPLAY 0.680851 (-913 1183);
PAINT GREEN (-913 1183);
FORCEPROP 2 LAST CDS_LIB standard
J 0
(-975 1175);
DISPLAY INVISIBLE (-975 1175);
FORCEPROP 1 LAST BODY_TYPE PLUMBING
J 2
(-975 1225);
DISPLAY 0.872340 (-975 1225);
PAINT GREEN (-975 1225);
DISPLAY INVISIBLE (-975 1225);
FORCEPROP 1 LAST HDL_TAP TRUE
J 2
(-1300 1050);
DISPLAY 0.872340 (-1300 1050);
DISPLAY INVISIBLE (-1300 1050);
FORCEPROP 1 LAST PATH I31
J 2
(-973 1175);
DISPLAY 0.872340 (-973 1175);
PAINT GREEN (-973 1175);
DISPLAY INVISIBLE (-973 1175);
FORCEADD TAP..1
R 2
(-975 1225);
FORCEPROP 3 LASTPIN (-925 1225) SIG_NAME M_F_CPU1_SB_DQ<15>
J 0
(-915 1235);
DISPLAY 0.659574 (-915 1235);
PAINT MONO (-915 1235);
DISPLAY INVISIBLE (-915 1235);
FORCEPROP 1 LASTPIN (-925 1225) BN 15
J 2
(-913 1233);
DISPLAY 0.680851 (-913 1233);
PAINT GREEN (-913 1233);
FORCEPROP 2 LAST CDS_LIB standard
J 0
(-975 1225);
DISPLAY INVISIBLE (-975 1225);
FORCEPROP 1 LAST BODY_TYPE PLUMBING
J 2
(-975 1275);
DISPLAY 0.872340 (-975 1275);
PAINT GREEN (-975 1275);
DISPLAY INVISIBLE (-975 1275);
FORCEPROP 1 LAST HDL_TAP TRUE
J 2
(-1300 1100);
DISPLAY 0.872340 (-1300 1100);
DISPLAY INVISIBLE (-1300 1100);
FORCEPROP 1 LAST PATH I32
J 2
(-973 1225);
DISPLAY 0.872340 (-973 1225);
PAINT GREEN (-973 1225);
DISPLAY INVISIBLE (-973 1225);
FORCEADD TAP..1
R 2
(-975 1275);
FORCEPROP 3 LASTPIN (-925 1275) SIG_NAME M_F_CPU1_SB_DQ<16>
J 0
(-915 1285);
DISPLAY 0.659574 (-915 1285);
PAINT MONO (-915 1285);
DISPLAY INVISIBLE (-915 1285);
FORCEPROP 1 LASTPIN (-925 1275) BN 16
J 2
(-913 1283);
DISPLAY 0.680851 (-913 1283);
PAINT GREEN (-913 1283);
FORCEPROP 2 LAST CDS_LIB standard
J 0
(-975 1275);
DISPLAY INVISIBLE (-975 1275);
FORCEPROP 1 LAST BODY_TYPE PLUMBING
J 2
(-975 1325);
DISPLAY 0.872340 (-975 1325);
PAINT GREEN (-975 1325);
DISPLAY INVISIBLE (-975 1325);
FORCEPROP 1 LAST HDL_TAP TRUE
J 2
(-1300 1150);
DISPLAY 0.872340 (-1300 1150);
DISPLAY INVISIBLE (-1300 1150);
FORCEPROP 1 LAST PATH I33
J 2
(-973 1275);
DISPLAY 0.872340 (-973 1275);
PAINT GREEN (-973 1275);
DISPLAY INVISIBLE (-973 1275);
FORCEADD TAP..1
R 2
(-975 1375);
FORCEPROP 3 LASTPIN (-925 1375) SIG_NAME M_F_CPU1_SB_DQ<18>
J 0
(-915 1385);
DISPLAY 0.659574 (-915 1385);
PAINT MONO (-915 1385);
DISPLAY INVISIBLE (-915 1385);
FORCEPROP 1 LASTPIN (-925 1375) BN 18
J 2
(-913 1383);
DISPLAY 0.680851 (-913 1383);
PAINT GREEN (-913 1383);
FORCEPROP 2 LAST CDS_LIB standard
J 0
(-975 1375);
DISPLAY INVISIBLE (-975 1375);
FORCEPROP 1 LAST BODY_TYPE PLUMBING
J 2
(-975 1425);
DISPLAY 0.872340 (-975 1425);
PAINT GREEN (-975 1425);
DISPLAY INVISIBLE (-975 1425);
FORCEPROP 1 LAST HDL_TAP TRUE
J 2
(-1300 1250);
DISPLAY 0.872340 (-1300 1250);
DISPLAY INVISIBLE (-1300 1250);
FORCEPROP 1 LAST PATH I34
J 2
(-973 1375);
DISPLAY 0.872340 (-973 1375);
PAINT GREEN (-973 1375);
DISPLAY INVISIBLE (-973 1375);
FORCEADD TAP..1
R 2
(-975 1425);
FORCEPROP 3 LASTPIN (-925 1425) SIG_NAME M_F_CPU1_SB_DQ<19>
J 0
(-915 1435);
DISPLAY 0.659574 (-915 1435);
PAINT MONO (-915 1435);
DISPLAY INVISIBLE (-915 1435);
FORCEPROP 1 LASTPIN (-925 1425) BN 19
J 2
(-913 1433);
DISPLAY 0.680851 (-913 1433);
PAINT GREEN (-913 1433);
FORCEPROP 2 LAST CDS_LIB standard
J 0
(-975 1425);
DISPLAY INVISIBLE (-975 1425);
FORCEPROP 1 LAST BODY_TYPE PLUMBING
J 2
(-975 1475);
DISPLAY 0.872340 (-975 1475);
PAINT GREEN (-975 1475);
DISPLAY INVISIBLE (-975 1475);
FORCEPROP 1 LAST HDL_TAP TRUE
J 2
(-1300 1300);
DISPLAY 0.872340 (-1300 1300);
DISPLAY INVISIBLE (-1300 1300);
FORCEPROP 1 LAST PATH I35
J 2
(-973 1425);
DISPLAY 0.872340 (-973 1425);
PAINT GREEN (-973 1425);
DISPLAY INVISIBLE (-973 1425);
FORCEADD TAP..1
R 2
(-975 1325);
FORCEPROP 3 LASTPIN (-925 1325) SIG_NAME M_F_CPU1_SB_DQ<17>
J 0
(-915 1335);
DISPLAY 0.659574 (-915 1335);
PAINT MONO (-915 1335);
DISPLAY INVISIBLE (-915 1335);
FORCEPROP 1 LASTPIN (-925 1325) BN 17
J 2
(-913 1333);
DISPLAY 0.680851 (-913 1333);
PAINT GREEN (-913 1333);
FORCEPROP 2 LAST CDS_LIB standard
J 0
(-975 1325);
DISPLAY INVISIBLE (-975 1325);
FORCEPROP 1 LAST BODY_TYPE PLUMBING
J 2
(-975 1375);
DISPLAY 0.872340 (-975 1375);
PAINT GREEN (-975 1375);
DISPLAY INVISIBLE (-975 1375);
FORCEPROP 1 LAST HDL_TAP TRUE
J 2
(-1300 1200);
DISPLAY 0.872340 (-1300 1200);
DISPLAY INVISIBLE (-1300 1200);
FORCEPROP 1 LAST PATH I36
J 2
(-973 1325);
DISPLAY 0.872340 (-973 1325);
PAINT GREEN (-973 1325);
DISPLAY INVISIBLE (-973 1325);
FORCEADD TAP..1
R 2
(-975 1525);
FORCEPROP 3 LASTPIN (-925 1525) SIG_NAME M_F_CPU1_SB_DQ<21>
J 0
(-915 1535);
DISPLAY 0.659574 (-915 1535);
PAINT MONO (-915 1535);
DISPLAY INVISIBLE (-915 1535);
FORCEPROP 1 LASTPIN (-925 1525) BN 21
J 2
(-913 1533);
DISPLAY 0.680851 (-913 1533);
PAINT GREEN (-913 1533);
FORCEPROP 2 LAST CDS_LIB standard
J 0
(-975 1525);
DISPLAY INVISIBLE (-975 1525);
FORCEPROP 1 LAST BODY_TYPE PLUMBING
J 2
(-975 1575);
DISPLAY 0.872340 (-975 1575);
PAINT GREEN (-975 1575);
DISPLAY INVISIBLE (-975 1575);
FORCEPROP 1 LAST HDL_TAP TRUE
J 2
(-1300 1400);
DISPLAY 0.872340 (-1300 1400);
DISPLAY INVISIBLE (-1300 1400);
FORCEPROP 1 LAST PATH I37
J 2
(-973 1525);
DISPLAY 0.872340 (-973 1525);
PAINT GREEN (-973 1525);
DISPLAY INVISIBLE (-973 1525);
FORCEADD TAP..1
R 2
(-975 1475);
FORCEPROP 3 LASTPIN (-925 1475) SIG_NAME M_F_CPU1_SB_DQ<20>
J 0
(-915 1485);
DISPLAY 0.659574 (-915 1485);
PAINT MONO (-915 1485);
DISPLAY INVISIBLE (-915 1485);
FORCEPROP 1 LASTPIN (-925 1475) BN 20
J 2
(-913 1483);
DISPLAY 0.680851 (-913 1483);
PAINT GREEN (-913 1483);
FORCEPROP 2 LAST CDS_LIB standard
J 0
(-975 1475);
DISPLAY INVISIBLE (-975 1475);
FORCEPROP 1 LAST BODY_TYPE PLUMBING
J 2
(-975 1525);
DISPLAY 0.872340 (-975 1525);
PAINT GREEN (-975 1525);
DISPLAY INVISIBLE (-975 1525);
FORCEPROP 1 LAST HDL_TAP TRUE
J 2
(-1300 1350);
DISPLAY 0.872340 (-1300 1350);
DISPLAY INVISIBLE (-1300 1350);
FORCEPROP 1 LAST PATH I38
J 2
(-973 1475);
DISPLAY 0.872340 (-973 1475);
PAINT GREEN (-973 1475);
DISPLAY INVISIBLE (-973 1475);
FORCEADD TAP..1
R 2
(-975 1575);
FORCEPROP 3 LASTPIN (-925 1575) SIG_NAME M_F_CPU1_SB_DQ<22>
J 0
(-915 1585);
DISPLAY 0.659574 (-915 1585);
PAINT MONO (-915 1585);
DISPLAY INVISIBLE (-915 1585);
FORCEPROP 1 LASTPIN (-925 1575) BN 22
J 2
(-913 1583);
DISPLAY 0.680851 (-913 1583);
PAINT GREEN (-913 1583);
FORCEPROP 2 LAST CDS_LIB standard
J 0
(-975 1575);
DISPLAY INVISIBLE (-975 1575);
FORCEPROP 1 LAST BODY_TYPE PLUMBING
J 2
(-975 1625);
DISPLAY 0.872340 (-975 1625);
PAINT GREEN (-975 1625);
DISPLAY INVISIBLE (-975 1625);
FORCEPROP 1 LAST HDL_TAP TRUE
J 2
(-1300 1450);
DISPLAY 0.872340 (-1300 1450);
DISPLAY INVISIBLE (-1300 1450);
FORCEPROP 1 LAST PATH I39
J 2
(-973 1575);
DISPLAY 0.872340 (-973 1575);
PAINT GREEN (-973 1575);
DISPLAY INVISIBLE (-973 1575);
FORCEADD TAP..1
R 2
(-975 -175);
FORCEPROP 3 LASTPIN (-925 -175) SIG_NAME M_F_CPU1_CLK_DN<0>
J 0
(-915 -165);
DISPLAY 0.659574 (-915 -165);
PAINT MONO (-915 -165);
DISPLAY INVISIBLE (-915 -165);
FORCEPROP 1 LASTPIN (-925 -175) BN 0
J 2
(-913 -167);
DISPLAY 0.680851 (-913 -167);
PAINT GREEN (-913 -167);
FORCEPROP 2 LAST CDS_LIB standard
J 0
(-975 -175);
DISPLAY INVISIBLE (-975 -175);
FORCEPROP 1 LAST BODY_TYPE PLUMBING
J 2
(-975 -125);
DISPLAY 0.872340 (-975 -125);
PAINT GREEN (-975 -125);
DISPLAY INVISIBLE (-975 -125);
FORCEPROP 1 LAST HDL_TAP TRUE
J 2
(-1300 -300);
DISPLAY 0.872340 (-1300 -300);
DISPLAY INVISIBLE (-1300 -300);
FORCEPROP 1 LAST PATH I4
J 2
(-973 -175);
DISPLAY 0.872340 (-973 -175);
PAINT GREEN (-973 -175);
DISPLAY INVISIBLE (-973 -175);
FORCEADD TAP..1
R 2
(-975 1625);
FORCEPROP 3 LASTPIN (-925 1625) SIG_NAME M_F_CPU1_SB_DQ<23>
J 0
(-915 1635);
DISPLAY 0.659574 (-915 1635);
PAINT MONO (-915 1635);
DISPLAY INVISIBLE (-915 1635);
FORCEPROP 1 LASTPIN (-925 1625) BN 23
J 2
(-913 1633);
DISPLAY 0.680851 (-913 1633);
PAINT GREEN (-913 1633);
FORCEPROP 2 LAST CDS_LIB standard
J 0
(-975 1625);
DISPLAY INVISIBLE (-975 1625);
FORCEPROP 1 LAST BODY_TYPE PLUMBING
J 2
(-975 1675);
DISPLAY 0.872340 (-975 1675);
PAINT GREEN (-975 1675);
DISPLAY INVISIBLE (-975 1675);
FORCEPROP 1 LAST HDL_TAP TRUE
J 2
(-1300 1500);
DISPLAY 0.872340 (-1300 1500);
DISPLAY INVISIBLE (-1300 1500);
FORCEPROP 1 LAST PATH I40
J 2
(-973 1625);
DISPLAY 0.872340 (-973 1625);
PAINT GREEN (-973 1625);
DISPLAY INVISIBLE (-973 1625);
FORCEADD TAP..1
R 2
(-975 1675);
FORCEPROP 3 LASTPIN (-925 1675) SIG_NAME M_F_CPU1_SB_DQ<24>
J 0
(-915 1685);
DISPLAY 0.659574 (-915 1685);
PAINT MONO (-915 1685);
DISPLAY INVISIBLE (-915 1685);
FORCEPROP 1 LASTPIN (-925 1675) BN 24
J 2
(-913 1683);
DISPLAY 0.680851 (-913 1683);
PAINT GREEN (-913 1683);
FORCEPROP 2 LAST CDS_LIB standard
J 0
(-975 1675);
DISPLAY INVISIBLE (-975 1675);
FORCEPROP 1 LAST BODY_TYPE PLUMBING
J 2
(-975 1725);
DISPLAY 0.872340 (-975 1725);
PAINT GREEN (-975 1725);
DISPLAY INVISIBLE (-975 1725);
FORCEPROP 1 LAST HDL_TAP TRUE
J 2
(-1300 1550);
DISPLAY 0.872340 (-1300 1550);
DISPLAY INVISIBLE (-1300 1550);
FORCEPROP 1 LAST PATH I41
J 2
(-973 1675);
DISPLAY 0.872340 (-973 1675);
PAINT GREEN (-973 1675);
DISPLAY INVISIBLE (-973 1675);
FORCEADD TAP..1
R 2
(-975 1725);
FORCEPROP 3 LASTPIN (-925 1725) SIG_NAME M_F_CPU1_SB_DQ<25>
J 0
(-915 1735);
DISPLAY 0.659574 (-915 1735);
PAINT MONO (-915 1735);
DISPLAY INVISIBLE (-915 1735);
FORCEPROP 1 LASTPIN (-925 1725) BN 25
J 2
(-913 1733);
DISPLAY 0.680851 (-913 1733);
PAINT GREEN (-913 1733);
FORCEPROP 2 LAST CDS_LIB standard
J 0
(-975 1725);
DISPLAY INVISIBLE (-975 1725);
FORCEPROP 1 LAST BODY_TYPE PLUMBING
J 2
(-975 1775);
DISPLAY 0.872340 (-975 1775);
PAINT GREEN (-975 1775);
DISPLAY INVISIBLE (-975 1775);
FORCEPROP 1 LAST HDL_TAP TRUE
J 2
(-1300 1600);
DISPLAY 0.872340 (-1300 1600);
DISPLAY INVISIBLE (-1300 1600);
FORCEPROP 1 LAST PATH I42
J 2
(-973 1725);
DISPLAY 0.872340 (-973 1725);
PAINT GREEN (-973 1725);
DISPLAY INVISIBLE (-973 1725);
FORCEADD TAP..1
R 2
(-975 1775);
FORCEPROP 3 LASTPIN (-925 1775) SIG_NAME M_F_CPU1_SB_DQ<26>
J 0
(-915 1785);
DISPLAY 0.659574 (-915 1785);
PAINT MONO (-915 1785);
DISPLAY INVISIBLE (-915 1785);
FORCEPROP 1 LASTPIN (-925 1775) BN 26
J 2
(-913 1783);
DISPLAY 0.680851 (-913 1783);
PAINT GREEN (-913 1783);
FORCEPROP 2 LAST CDS_LIB standard
J 0
(-975 1775);
DISPLAY INVISIBLE (-975 1775);
FORCEPROP 1 LAST BODY_TYPE PLUMBING
J 2
(-975 1825);
DISPLAY 0.872340 (-975 1825);
PAINT GREEN (-975 1825);
DISPLAY INVISIBLE (-975 1825);
FORCEPROP 1 LAST HDL_TAP TRUE
J 2
(-1300 1650);
DISPLAY 0.872340 (-1300 1650);
DISPLAY INVISIBLE (-1300 1650);
FORCEPROP 1 LAST PATH I43
J 2
(-973 1775);
DISPLAY 0.872340 (-973 1775);
PAINT GREEN (-973 1775);
DISPLAY INVISIBLE (-973 1775);
FORCEADD TAP..1
R 2
(-975 1825);
FORCEPROP 3 LASTPIN (-925 1825) SIG_NAME M_F_CPU1_SB_DQ<27>
J 0
(-915 1835);
DISPLAY 0.659574 (-915 1835);
PAINT MONO (-915 1835);
DISPLAY INVISIBLE (-915 1835);
FORCEPROP 1 LASTPIN (-925 1825) BN 27
J 2
(-913 1833);
DISPLAY 0.680851 (-913 1833);
PAINT GREEN (-913 1833);
FORCEPROP 2 LAST CDS_LIB standard
J 0
(-975 1825);
DISPLAY INVISIBLE (-975 1825);
FORCEPROP 1 LAST BODY_TYPE PLUMBING
J 2
(-975 1875);
DISPLAY 0.872340 (-975 1875);
PAINT GREEN (-975 1875);
DISPLAY INVISIBLE (-975 1875);
FORCEPROP 1 LAST HDL_TAP TRUE
J 2
(-1300 1700);
DISPLAY 0.872340 (-1300 1700);
DISPLAY INVISIBLE (-1300 1700);
FORCEPROP 1 LAST PATH I44
J 2
(-973 1825);
DISPLAY 0.872340 (-973 1825);
PAINT GREEN (-973 1825);
DISPLAY INVISIBLE (-973 1825);
FORCEADD TAP..1
R 2
(-975 1875);
FORCEPROP 3 LASTPIN (-925 1875) SIG_NAME M_F_CPU1_SB_DQ<28>
J 0
(-915 1885);
DISPLAY 0.659574 (-915 1885);
PAINT MONO (-915 1885);
DISPLAY INVISIBLE (-915 1885);
FORCEPROP 1 LASTPIN (-925 1875) BN 28
J 2
(-913 1883);
DISPLAY 0.680851 (-913 1883);
PAINT GREEN (-913 1883);
FORCEPROP 2 LAST CDS_LIB standard
J 0
(-975 1875);
DISPLAY INVISIBLE (-975 1875);
FORCEPROP 1 LAST BODY_TYPE PLUMBING
J 2
(-975 1925);
DISPLAY 0.872340 (-975 1925);
PAINT GREEN (-975 1925);
DISPLAY INVISIBLE (-975 1925);
FORCEPROP 1 LAST HDL_TAP TRUE
J 2
(-1300 1750);
DISPLAY 0.872340 (-1300 1750);
DISPLAY INVISIBLE (-1300 1750);
FORCEPROP 1 LAST PATH I45
J 2
(-973 1875);
DISPLAY 0.872340 (-973 1875);
PAINT GREEN (-973 1875);
DISPLAY INVISIBLE (-973 1875);
FORCEADD TAP..1
R 2
(-975 1925);
FORCEPROP 3 LASTPIN (-925 1925) SIG_NAME M_F_CPU1_SB_DQ<29>
J 0
(-915 1935);
DISPLAY 0.659574 (-915 1935);
PAINT MONO (-915 1935);
DISPLAY INVISIBLE (-915 1935);
FORCEPROP 1 LASTPIN (-925 1925) BN 29
J 2
(-913 1933);
DISPLAY 0.680851 (-913 1933);
PAINT GREEN (-913 1933);
FORCEPROP 2 LAST CDS_LIB standard
J 0
(-975 1925);
DISPLAY INVISIBLE (-975 1925);
FORCEPROP 1 LAST BODY_TYPE PLUMBING
J 2
(-975 1975);
DISPLAY 0.872340 (-975 1975);
PAINT GREEN (-975 1975);
DISPLAY INVISIBLE (-975 1975);
FORCEPROP 1 LAST HDL_TAP TRUE
J 2
(-1300 1800);
DISPLAY 0.872340 (-1300 1800);
DISPLAY INVISIBLE (-1300 1800);
FORCEPROP 1 LAST PATH I46
J 2
(-973 1925);
DISPLAY 0.872340 (-973 1925);
PAINT GREEN (-973 1925);
DISPLAY INVISIBLE (-973 1925);
FORCEADD TAP..1
R 2
(-975 2025);
FORCEPROP 3 LASTPIN (-925 2025) SIG_NAME M_F_CPU1_SB_DQ<31>
J 0
(-915 2035);
DISPLAY 0.659574 (-915 2035);
PAINT MONO (-915 2035);
DISPLAY INVISIBLE (-915 2035);
FORCEPROP 1 LASTPIN (-925 2025) BN 31
J 2
(-913 2033);
DISPLAY 0.680851 (-913 2033);
PAINT GREEN (-913 2033);
FORCEPROP 2 LAST CDS_LIB standard
J 0
(-975 2025);
DISPLAY INVISIBLE (-975 2025);
FORCEPROP 1 LAST BODY_TYPE PLUMBING
J 2
(-975 2075);
DISPLAY 0.872340 (-975 2075);
PAINT GREEN (-975 2075);
DISPLAY INVISIBLE (-975 2075);
FORCEPROP 1 LAST HDL_TAP TRUE
J 2
(-1300 1900);
DISPLAY 0.872340 (-1300 1900);
DISPLAY INVISIBLE (-1300 1900);
FORCEPROP 1 LAST PATH I47
J 2
(-973 2025);
DISPLAY 0.872340 (-973 2025);
PAINT GREEN (-973 2025);
DISPLAY INVISIBLE (-973 2025);
FORCEADD TAP..1
R 2
(-975 1975);
FORCEPROP 3 LASTPIN (-925 1975) SIG_NAME M_F_CPU1_SB_DQ<30>
J 0
(-915 1985);
DISPLAY 0.659574 (-915 1985);
PAINT MONO (-915 1985);
DISPLAY INVISIBLE (-915 1985);
FORCEPROP 1 LASTPIN (-925 1975) BN 30
J 2
(-913 1983);
DISPLAY 0.680851 (-913 1983);
PAINT GREEN (-913 1983);
FORCEPROP 2 LAST CDS_LIB standard
J 0
(-975 1975);
DISPLAY INVISIBLE (-975 1975);
FORCEPROP 1 LAST BODY_TYPE PLUMBING
J 2
(-975 2025);
DISPLAY 0.872340 (-975 2025);
PAINT GREEN (-975 2025);
DISPLAY INVISIBLE (-975 2025);
FORCEPROP 1 LAST HDL_TAP TRUE
J 2
(-1300 1850);
DISPLAY 0.872340 (-1300 1850);
DISPLAY INVISIBLE (-1300 1850);
FORCEPROP 1 LAST PATH I48
J 2
(-973 1975);
DISPLAY 0.872340 (-973 1975);
PAINT GREEN (-973 1975);
DISPLAY INVISIBLE (-973 1975);
FORCEADD TAP..1
R 2
(-975 2175);
FORCEPROP 3 LASTPIN (-925 2175) SIG_NAME M_F_CPU1_SA_CB<2>
J 0
(-915 2185);
DISPLAY 0.659574 (-915 2185);
PAINT MONO (-915 2185);
DISPLAY INVISIBLE (-915 2185);
FORCEPROP 1 LASTPIN (-925 2175) BN 2
J 2
(-913 2183);
DISPLAY 0.680851 (-913 2183);
PAINT GREEN (-913 2183);
FORCEPROP 2 LAST CDS_LIB standard
J 0
(-975 2175);
DISPLAY INVISIBLE (-975 2175);
FORCEPROP 1 LAST BODY_TYPE PLUMBING
J 2
(-975 2225);
DISPLAY 0.872340 (-975 2225);
PAINT GREEN (-975 2225);
DISPLAY INVISIBLE (-975 2225);
FORCEPROP 1 LAST HDL_TAP TRUE
J 2
(-1300 2050);
DISPLAY 0.872340 (-1300 2050);
DISPLAY INVISIBLE (-1300 2050);
FORCEPROP 1 LAST PATH I49
J 2
(-973 2175);
DISPLAY 0.872340 (-973 2175);
PAINT GREEN (-973 2175);
DISPLAY INVISIBLE (-973 2175);
FORCEADD TAP..1
R 2
(-975 125);
FORCEPROP 3 LASTPIN (-925 125) SIG_NAME M_F_CPU1_SB_CB<1>
J 0
(-915 135);
DISPLAY 0.659574 (-915 135);
PAINT MONO (-915 135);
DISPLAY INVISIBLE (-915 135);
FORCEPROP 1 LASTPIN (-925 125) BN 1
J 2
(-913 133);
DISPLAY 0.680851 (-913 133);
PAINT GREEN (-913 133);
FORCEPROP 2 LAST CDS_LIB standard
J 0
(-975 125);
DISPLAY INVISIBLE (-975 125);
FORCEPROP 1 LAST BODY_TYPE PLUMBING
J 2
(-975 175);
DISPLAY 0.872340 (-975 175);
PAINT GREEN (-975 175);
DISPLAY INVISIBLE (-975 175);
FORCEPROP 1 LAST HDL_TAP TRUE
J 2
(-1300 0);
DISPLAY 0.872340 (-1300 0);
DISPLAY INVISIBLE (-1300 0);
FORCEPROP 1 LAST PATH I5
J 2
(-973 125);
DISPLAY 0.872340 (-973 125);
PAINT GREEN (-973 125);
DISPLAY INVISIBLE (-973 125);
FORCEADD TAP..1
R 2
(-975 2125);
FORCEPROP 3 LASTPIN (-925 2125) SIG_NAME M_F_CPU1_SA_CB<1>
J 0
(-915 2135);
DISPLAY 0.659574 (-915 2135);
PAINT MONO (-915 2135);
DISPLAY INVISIBLE (-915 2135);
FORCEPROP 1 LASTPIN (-925 2125) BN 1
J 2
(-913 2133);
DISPLAY 0.680851 (-913 2133);
PAINT GREEN (-913 2133);
FORCEPROP 2 LAST CDS_LIB standard
J 0
(-975 2125);
DISPLAY INVISIBLE (-975 2125);
FORCEPROP 1 LAST BODY_TYPE PLUMBING
J 2
(-975 2175);
DISPLAY 0.872340 (-975 2175);
PAINT GREEN (-975 2175);
DISPLAY INVISIBLE (-975 2175);
FORCEPROP 1 LAST HDL_TAP TRUE
J 2
(-1300 2000);
DISPLAY 0.872340 (-1300 2000);
DISPLAY INVISIBLE (-1300 2000);
FORCEPROP 1 LAST PATH I50
J 2
(-973 2125);
DISPLAY 0.872340 (-973 2125);
PAINT GREEN (-973 2125);
DISPLAY INVISIBLE (-973 2125);
FORCEADD TAP..1
R 2
(-975 2075);
FORCEPROP 3 LASTPIN (-925 2075) SIG_NAME M_F_CPU1_SA_CB<0>
J 0
(-915 2085);
DISPLAY 0.659574 (-915 2085);
PAINT MONO (-915 2085);
DISPLAY INVISIBLE (-915 2085);
FORCEPROP 1 LASTPIN (-925 2075) BN 0
J 2
(-913 2083);
DISPLAY 0.680851 (-913 2083);
PAINT GREEN (-913 2083);
FORCEPROP 2 LAST CDS_LIB standard
J 0
(-975 2075);
DISPLAY INVISIBLE (-975 2075);
FORCEPROP 1 LAST BODY_TYPE PLUMBING
J 2
(-975 2125);
DISPLAY 0.872340 (-975 2125);
PAINT GREEN (-975 2125);
DISPLAY INVISIBLE (-975 2125);
FORCEPROP 1 LAST HDL_TAP TRUE
J 2
(-1300 1950);
DISPLAY 0.872340 (-1300 1950);
DISPLAY INVISIBLE (-1300 1950);
FORCEPROP 1 LAST PATH I51
J 2
(-973 2075);
DISPLAY 0.872340 (-973 2075);
PAINT GREEN (-973 2075);
DISPLAY INVISIBLE (-973 2075);
FORCEADD OFFPAGE..3
R 2
(-2000 2450);
FORCEPROP 2 LAST $XR1 109 
J 0
(-2430 2450);
DISPLAY 0.638298 (-2430 2450);
PAINT MONO (-2430 2450);
FORCEPROP 2 LAST $XR0 108 
J 0
(-2310 2450);
DISPLAY 0.638298 (-2310 2450);
PAINT MONO (-2310 2450);
FORCEPROP 2 LAST CDS_LIB standard
J 0
(-2000 2450);
DISPLAY INVISIBLE (-2000 2450);
FORCEPROP 1 LAST OFFPAGE TRUE
J 2
(-2325 2325);
DISPLAY 0.872340 (-2325 2325);
DISPLAY INVISIBLE (-2325 2325);
FORCEPROP 1 LAST COMMENT_BODY TRUE
J 2
(-1950 2350);
DISPLAY 0.872340 (-1950 2350);
PAINT GREEN (-1950 2350);
DISPLAY INVISIBLE (-1950 2350);
FORCEPROP 2 LAST PATH I52
J 0
(-1950 2525);
DISPLAY 1.021277 (-1950 2525);
DISPLAY INVISIBLE (-1950 2525);
FORCEADD OFFPAGE..3
R 2
(-2000 4050);
FORCEPROP 2 LAST $XR1 109 
J 0
(-2430 4050);
DISPLAY 0.638298 (-2430 4050);
PAINT MONO (-2430 4050);
FORCEPROP 2 LAST $XR0 108 
J 0
(-2310 4050);
DISPLAY 0.638298 (-2310 4050);
PAINT MONO (-2310 4050);
FORCEPROP 2 LAST CDS_LIB standard
J 0
(-2000 4050);
DISPLAY INVISIBLE (-2000 4050);
FORCEPROP 1 LAST OFFPAGE TRUE
J 2
(-2325 3925);
DISPLAY 0.872340 (-2325 3925);
DISPLAY INVISIBLE (-2325 3925);
FORCEPROP 1 LAST COMMENT_BODY TRUE
J 2
(-1950 3950);
DISPLAY 0.872340 (-1950 3950);
PAINT GREEN (-1950 3950);
DISPLAY INVISIBLE (-1950 3950);
FORCEPROP 2 LAST PATH I53
J 0
(-1950 4125);
DISPLAY 1.021277 (-1950 4125);
DISPLAY INVISIBLE (-1950 4125);
FORCEADD TAP..1
R 2
(-975 2275);
FORCEPROP 3 LASTPIN (-925 2275) SIG_NAME M_F_CPU1_SA_CB<4>
J 0
(-915 2285);
DISPLAY 0.659574 (-915 2285);
PAINT MONO (-915 2285);
DISPLAY INVISIBLE (-915 2285);
FORCEPROP 1 LASTPIN (-925 2275) BN 4
J 2
(-913 2283);
DISPLAY 0.680851 (-913 2283);
PAINT GREEN (-913 2283);
FORCEPROP 2 LAST CDS_LIB standard
J 0
(-975 2275);
DISPLAY INVISIBLE (-975 2275);
FORCEPROP 1 LAST BODY_TYPE PLUMBING
J 2
(-975 2325);
DISPLAY 0.872340 (-975 2325);
PAINT GREEN (-975 2325);
DISPLAY INVISIBLE (-975 2325);
FORCEPROP 1 LAST HDL_TAP TRUE
J 2
(-1300 2150);
DISPLAY 0.872340 (-1300 2150);
DISPLAY INVISIBLE (-1300 2150);
FORCEPROP 1 LAST PATH I54
J 2
(-973 2275);
DISPLAY 0.872340 (-973 2275);
PAINT GREEN (-973 2275);
DISPLAY INVISIBLE (-973 2275);
FORCEADD TAP..1
R 2
(-975 2325);
FORCEPROP 3 LASTPIN (-925 2325) SIG_NAME M_F_CPU1_SA_CB<5>
J 0
(-915 2335);
DISPLAY 0.659574 (-915 2335);
PAINT MONO (-915 2335);
DISPLAY INVISIBLE (-915 2335);
FORCEPROP 1 LASTPIN (-925 2325) BN 5
J 2
(-913 2333);
DISPLAY 0.680851 (-913 2333);
PAINT GREEN (-913 2333);
FORCEPROP 2 LAST CDS_LIB standard
J 0
(-975 2325);
DISPLAY INVISIBLE (-975 2325);
FORCEPROP 1 LAST BODY_TYPE PLUMBING
J 2
(-975 2375);
DISPLAY 0.872340 (-975 2375);
PAINT GREEN (-975 2375);
DISPLAY INVISIBLE (-975 2375);
FORCEPROP 1 LAST HDL_TAP TRUE
J 2
(-1300 2200);
DISPLAY 0.872340 (-1300 2200);
DISPLAY INVISIBLE (-1300 2200);
FORCEPROP 1 LAST PATH I55
J 2
(-973 2325);
DISPLAY 0.872340 (-973 2325);
PAINT GREEN (-973 2325);
DISPLAY INVISIBLE (-973 2325);
FORCEADD TAP..1
R 2
(-975 2225);
FORCEPROP 3 LASTPIN (-925 2225) SIG_NAME M_F_CPU1_SA_CB<3>
J 0
(-915 2235);
DISPLAY 0.659574 (-915 2235);
PAINT MONO (-915 2235);
DISPLAY INVISIBLE (-915 2235);
FORCEPROP 1 LASTPIN (-925 2225) BN 3
J 2
(-913 2233);
DISPLAY 0.680851 (-913 2233);
PAINT GREEN (-913 2233);
FORCEPROP 2 LAST CDS_LIB standard
J 0
(-975 2225);
DISPLAY INVISIBLE (-975 2225);
FORCEPROP 1 LAST BODY_TYPE PLUMBING
J 2
(-975 2275);
DISPLAY 0.872340 (-975 2275);
PAINT GREEN (-975 2275);
DISPLAY INVISIBLE (-975 2275);
FORCEPROP 1 LAST HDL_TAP TRUE
J 2
(-1300 2100);
DISPLAY 0.872340 (-1300 2100);
DISPLAY INVISIBLE (-1300 2100);
FORCEPROP 1 LAST PATH I56
J 2
(-973 2225);
DISPLAY 0.872340 (-973 2225);
PAINT GREEN (-973 2225);
DISPLAY INVISIBLE (-973 2225);
FORCEADD TAP..1
R 2
(-975 2425);
FORCEPROP 3 LASTPIN (-925 2425) SIG_NAME M_F_CPU1_SA_CB<7>
J 0
(-915 2435);
DISPLAY 0.659574 (-915 2435);
PAINT MONO (-915 2435);
DISPLAY INVISIBLE (-915 2435);
FORCEPROP 1 LASTPIN (-925 2425) BN 7
J 2
(-913 2433);
DISPLAY 0.680851 (-913 2433);
PAINT GREEN (-913 2433);
FORCEPROP 2 LAST CDS_LIB standard
J 0
(-975 2425);
DISPLAY INVISIBLE (-975 2425);
FORCEPROP 1 LAST BODY_TYPE PLUMBING
J 2
(-975 2475);
DISPLAY 0.872340 (-975 2475);
PAINT GREEN (-975 2475);
DISPLAY INVISIBLE (-975 2475);
FORCEPROP 1 LAST HDL_TAP TRUE
J 2
(-1300 2300);
DISPLAY 0.872340 (-1300 2300);
DISPLAY INVISIBLE (-1300 2300);
FORCEPROP 1 LAST PATH I57
J 2
(-973 2425);
DISPLAY 0.872340 (-973 2425);
PAINT GREEN (-973 2425);
DISPLAY INVISIBLE (-973 2425);
FORCEADD TAP..1
R 2
(-975 2375);
FORCEPROP 3 LASTPIN (-925 2375) SIG_NAME M_F_CPU1_SA_CB<6>
J 0
(-915 2385);
DISPLAY 0.659574 (-915 2385);
PAINT MONO (-915 2385);
DISPLAY INVISIBLE (-915 2385);
FORCEPROP 1 LASTPIN (-925 2375) BN 6
J 2
(-913 2383);
DISPLAY 0.680851 (-913 2383);
PAINT GREEN (-913 2383);
FORCEPROP 2 LAST CDS_LIB standard
J 0
(-975 2375);
DISPLAY INVISIBLE (-975 2375);
FORCEPROP 1 LAST BODY_TYPE PLUMBING
J 2
(-975 2425);
DISPLAY 0.872340 (-975 2425);
PAINT GREEN (-975 2425);
DISPLAY INVISIBLE (-975 2425);
FORCEPROP 1 LAST HDL_TAP TRUE
J 2
(-1300 2250);
DISPLAY 0.872340 (-1300 2250);
DISPLAY INVISIBLE (-1300 2250);
FORCEPROP 1 LAST PATH I58
J 2
(-973 2375);
DISPLAY 0.872340 (-973 2375);
PAINT GREEN (-973 2375);
DISPLAY INVISIBLE (-973 2375);
FORCEADD TAP..1
R 2
(-975 2525);
FORCEPROP 3 LASTPIN (-925 2525) SIG_NAME M_F_CPU1_SA_DQ<1>
J 0
(-915 2535);
DISPLAY 0.659574 (-915 2535);
PAINT MONO (-915 2535);
DISPLAY INVISIBLE (-915 2535);
FORCEPROP 1 LASTPIN (-925 2525) BN 1
J 2
(-913 2533);
DISPLAY 0.680851 (-913 2533);
PAINT GREEN (-913 2533);
FORCEPROP 2 LAST CDS_LIB standard
J 0
(-975 2525);
DISPLAY INVISIBLE (-975 2525);
FORCEPROP 1 LAST BODY_TYPE PLUMBING
J 2
(-975 2575);
DISPLAY 0.872340 (-975 2575);
PAINT GREEN (-975 2575);
DISPLAY INVISIBLE (-975 2575);
FORCEPROP 1 LAST HDL_TAP TRUE
J 2
(-1300 2400);
DISPLAY 0.872340 (-1300 2400);
DISPLAY INVISIBLE (-1300 2400);
FORCEPROP 1 LAST PATH I59
J 2
(-973 2525);
DISPLAY 0.872340 (-973 2525);
PAINT GREEN (-973 2525);
DISPLAY INVISIBLE (-973 2525);
FORCEADD TAP..1
R 2
(-975 75);
FORCEPROP 3 LASTPIN (-925 75) SIG_NAME M_F_CPU1_SB_CB<0>
J 0
(-915 85);
DISPLAY 0.659574 (-915 85);
PAINT MONO (-915 85);
DISPLAY INVISIBLE (-915 85);
FORCEPROP 1 LASTPIN (-925 75) BN 0
J 2
(-913 83);
DISPLAY 0.680851 (-913 83);
PAINT GREEN (-913 83);
FORCEPROP 2 LAST CDS_LIB standard
J 0
(-975 75);
DISPLAY INVISIBLE (-975 75);
FORCEPROP 1 LAST BODY_TYPE PLUMBING
J 2
(-975 125);
DISPLAY 0.872340 (-975 125);
PAINT GREEN (-975 125);
DISPLAY INVISIBLE (-975 125);
FORCEPROP 1 LAST HDL_TAP TRUE
J 2
(-1300 -50);
DISPLAY 0.872340 (-1300 -50);
DISPLAY INVISIBLE (-1300 -50);
FORCEPROP 1 LAST PATH I6
J 2
(-973 75);
DISPLAY 0.872340 (-973 75);
PAINT GREEN (-973 75);
DISPLAY INVISIBLE (-973 75);
FORCEADD TAP..1
R 2
(-975 2475);
FORCEPROP 3 LASTPIN (-925 2475) SIG_NAME M_F_CPU1_SA_DQ<0>
J 0
(-915 2485);
DISPLAY 0.659574 (-915 2485);
PAINT MONO (-915 2485);
DISPLAY INVISIBLE (-915 2485);
FORCEPROP 1 LASTPIN (-925 2475) BN 0
J 2
(-913 2483);
DISPLAY 0.680851 (-913 2483);
PAINT GREEN (-913 2483);
FORCEPROP 2 LAST CDS_LIB standard
J 0
(-975 2475);
DISPLAY INVISIBLE (-975 2475);
FORCEPROP 1 LAST BODY_TYPE PLUMBING
J 2
(-975 2525);
DISPLAY 0.872340 (-975 2525);
PAINT GREEN (-975 2525);
DISPLAY INVISIBLE (-975 2525);
FORCEPROP 1 LAST HDL_TAP TRUE
J 2
(-1300 2350);
DISPLAY 0.872340 (-1300 2350);
DISPLAY INVISIBLE (-1300 2350);
FORCEPROP 1 LAST PATH I60
J 2
(-973 2475);
DISPLAY 0.872340 (-973 2475);
PAINT GREEN (-973 2475);
DISPLAY INVISIBLE (-973 2475);
FORCEADD TAP..1
R 2
(-975 2575);
FORCEPROP 3 LASTPIN (-925 2575) SIG_NAME M_F_CPU1_SA_DQ<2>
J 0
(-915 2585);
DISPLAY 0.659574 (-915 2585);
PAINT MONO (-915 2585);
DISPLAY INVISIBLE (-915 2585);
FORCEPROP 1 LASTPIN (-925 2575) BN 2
J 2
(-913 2583);
DISPLAY 0.680851 (-913 2583);
PAINT GREEN (-913 2583);
FORCEPROP 2 LAST CDS_LIB standard
J 0
(-975 2575);
DISPLAY INVISIBLE (-975 2575);
FORCEPROP 1 LAST BODY_TYPE PLUMBING
J 2
(-975 2625);
DISPLAY 0.872340 (-975 2625);
PAINT GREEN (-975 2625);
DISPLAY INVISIBLE (-975 2625);
FORCEPROP 1 LAST HDL_TAP TRUE
J 2
(-1300 2450);
DISPLAY 0.872340 (-1300 2450);
DISPLAY INVISIBLE (-1300 2450);
FORCEPROP 1 LAST PATH I61
J 2
(-973 2575);
DISPLAY 0.872340 (-973 2575);
PAINT GREEN (-973 2575);
DISPLAY INVISIBLE (-973 2575);
FORCEADD TAP..1
R 2
(-975 2675);
FORCEPROP 3 LASTPIN (-925 2675) SIG_NAME M_F_CPU1_SA_DQ<4>
J 0
(-915 2685);
DISPLAY 0.659574 (-915 2685);
PAINT MONO (-915 2685);
DISPLAY INVISIBLE (-915 2685);
FORCEPROP 1 LASTPIN (-925 2675) BN 4
J 2
(-913 2683);
DISPLAY 0.680851 (-913 2683);
PAINT GREEN (-913 2683);
FORCEPROP 2 LAST CDS_LIB standard
J 0
(-975 2675);
DISPLAY INVISIBLE (-975 2675);
FORCEPROP 1 LAST BODY_TYPE PLUMBING
J 2
(-975 2725);
DISPLAY 0.872340 (-975 2725);
PAINT GREEN (-975 2725);
DISPLAY INVISIBLE (-975 2725);
FORCEPROP 1 LAST HDL_TAP TRUE
J 2
(-1300 2550);
DISPLAY 0.872340 (-1300 2550);
DISPLAY INVISIBLE (-1300 2550);
FORCEPROP 1 LAST PATH I62
J 2
(-973 2675);
DISPLAY 0.872340 (-973 2675);
PAINT GREEN (-973 2675);
DISPLAY INVISIBLE (-973 2675);
FORCEADD TAP..1
R 2
(-975 2625);
FORCEPROP 3 LASTPIN (-925 2625) SIG_NAME M_F_CPU1_SA_DQ<3>
J 0
(-915 2635);
DISPLAY 0.659574 (-915 2635);
PAINT MONO (-915 2635);
DISPLAY INVISIBLE (-915 2635);
FORCEPROP 1 LASTPIN (-925 2625) BN 3
J 2
(-913 2633);
DISPLAY 0.680851 (-913 2633);
PAINT GREEN (-913 2633);
FORCEPROP 2 LAST CDS_LIB standard
J 0
(-975 2625);
DISPLAY INVISIBLE (-975 2625);
FORCEPROP 1 LAST BODY_TYPE PLUMBING
J 2
(-975 2675);
DISPLAY 0.872340 (-975 2675);
PAINT GREEN (-975 2675);
DISPLAY INVISIBLE (-975 2675);
FORCEPROP 1 LAST HDL_TAP TRUE
J 2
(-1300 2500);
DISPLAY 0.872340 (-1300 2500);
DISPLAY INVISIBLE (-1300 2500);
FORCEPROP 1 LAST PATH I63
J 2
(-973 2625);
DISPLAY 0.872340 (-973 2625);
PAINT GREEN (-973 2625);
DISPLAY INVISIBLE (-973 2625);
FORCEADD TAP..1
R 2
(-975 2725);
FORCEPROP 3 LASTPIN (-925 2725) SIG_NAME M_F_CPU1_SA_DQ<5>
J 0
(-915 2735);
DISPLAY 0.659574 (-915 2735);
PAINT MONO (-915 2735);
DISPLAY INVISIBLE (-915 2735);
FORCEPROP 1 LASTPIN (-925 2725) BN 5
J 2
(-913 2733);
DISPLAY 0.680851 (-913 2733);
PAINT GREEN (-913 2733);
FORCEPROP 2 LAST CDS_LIB standard
J 0
(-975 2725);
DISPLAY INVISIBLE (-975 2725);
FORCEPROP 1 LAST BODY_TYPE PLUMBING
J 2
(-975 2775);
DISPLAY 0.872340 (-975 2775);
PAINT GREEN (-975 2775);
DISPLAY INVISIBLE (-975 2775);
FORCEPROP 1 LAST HDL_TAP TRUE
J 2
(-1300 2600);
DISPLAY 0.872340 (-1300 2600);
DISPLAY INVISIBLE (-1300 2600);
FORCEPROP 1 LAST PATH I64
J 2
(-973 2725);
DISPLAY 0.872340 (-973 2725);
PAINT GREEN (-973 2725);
DISPLAY INVISIBLE (-973 2725);
FORCEADD TAP..1
R 2
(-975 2825);
FORCEPROP 3 LASTPIN (-925 2825) SIG_NAME M_F_CPU1_SA_DQ<7>
J 0
(-915 2835);
DISPLAY 0.659574 (-915 2835);
PAINT MONO (-915 2835);
DISPLAY INVISIBLE (-915 2835);
FORCEPROP 1 LASTPIN (-925 2825) BN 7
J 2
(-913 2833);
DISPLAY 0.680851 (-913 2833);
PAINT GREEN (-913 2833);
FORCEPROP 2 LAST CDS_LIB standard
J 0
(-975 2825);
DISPLAY INVISIBLE (-975 2825);
FORCEPROP 1 LAST BODY_TYPE PLUMBING
J 2
(-975 2875);
DISPLAY 0.872340 (-975 2875);
PAINT GREEN (-975 2875);
DISPLAY INVISIBLE (-975 2875);
FORCEPROP 1 LAST HDL_TAP TRUE
J 2
(-1300 2700);
DISPLAY 0.872340 (-1300 2700);
DISPLAY INVISIBLE (-1300 2700);
FORCEPROP 1 LAST PATH I65
J 2
(-973 2825);
DISPLAY 0.872340 (-973 2825);
PAINT GREEN (-973 2825);
DISPLAY INVISIBLE (-973 2825);
FORCEADD TAP..1
R 2
(-975 2775);
FORCEPROP 3 LASTPIN (-925 2775) SIG_NAME M_F_CPU1_SA_DQ<6>
J 0
(-915 2785);
DISPLAY 0.659574 (-915 2785);
PAINT MONO (-915 2785);
DISPLAY INVISIBLE (-915 2785);
FORCEPROP 1 LASTPIN (-925 2775) BN 6
J 2
(-913 2783);
DISPLAY 0.680851 (-913 2783);
PAINT GREEN (-913 2783);
FORCEPROP 2 LAST CDS_LIB standard
J 0
(-975 2775);
DISPLAY INVISIBLE (-975 2775);
FORCEPROP 1 LAST BODY_TYPE PLUMBING
J 2
(-975 2825);
DISPLAY 0.872340 (-975 2825);
PAINT GREEN (-975 2825);
DISPLAY INVISIBLE (-975 2825);
FORCEPROP 1 LAST HDL_TAP TRUE
J 2
(-1300 2650);
DISPLAY 0.872340 (-1300 2650);
DISPLAY INVISIBLE (-1300 2650);
FORCEPROP 1 LAST PATH I66
J 2
(-973 2775);
DISPLAY 0.872340 (-973 2775);
PAINT GREEN (-973 2775);
DISPLAY INVISIBLE (-973 2775);
FORCEADD TAP..1
R 2
(-975 2925);
FORCEPROP 3 LASTPIN (-925 2925) SIG_NAME M_F_CPU1_SA_DQ<9>
J 0
(-915 2935);
DISPLAY 0.659574 (-915 2935);
PAINT MONO (-915 2935);
DISPLAY INVISIBLE (-915 2935);
FORCEPROP 1 LASTPIN (-925 2925) BN 9
J 2
(-913 2933);
DISPLAY 0.680851 (-913 2933);
PAINT GREEN (-913 2933);
FORCEPROP 2 LAST CDS_LIB standard
J 0
(-975 2925);
DISPLAY INVISIBLE (-975 2925);
FORCEPROP 1 LAST BODY_TYPE PLUMBING
J 2
(-975 2975);
DISPLAY 0.872340 (-975 2975);
PAINT GREEN (-975 2975);
DISPLAY INVISIBLE (-975 2975);
FORCEPROP 1 LAST HDL_TAP TRUE
J 2
(-1300 2800);
DISPLAY 0.872340 (-1300 2800);
DISPLAY INVISIBLE (-1300 2800);
FORCEPROP 1 LAST PATH I67
J 2
(-973 2925);
DISPLAY 0.872340 (-973 2925);
PAINT GREEN (-973 2925);
DISPLAY INVISIBLE (-973 2925);
FORCEADD TAP..1
R 2
(-975 2875);
FORCEPROP 3 LASTPIN (-925 2875) SIG_NAME M_F_CPU1_SA_DQ<8>
J 0
(-915 2885);
DISPLAY 0.659574 (-915 2885);
PAINT MONO (-915 2885);
DISPLAY INVISIBLE (-915 2885);
FORCEPROP 1 LASTPIN (-925 2875) BN 8
J 2
(-913 2883);
DISPLAY 0.680851 (-913 2883);
PAINT GREEN (-913 2883);
FORCEPROP 2 LAST CDS_LIB standard
J 0
(-975 2875);
DISPLAY INVISIBLE (-975 2875);
FORCEPROP 1 LAST BODY_TYPE PLUMBING
J 2
(-975 2925);
DISPLAY 0.872340 (-975 2925);
PAINT GREEN (-975 2925);
DISPLAY INVISIBLE (-975 2925);
FORCEPROP 1 LAST HDL_TAP TRUE
J 2
(-1300 2750);
DISPLAY 0.872340 (-1300 2750);
DISPLAY INVISIBLE (-1300 2750);
FORCEPROP 1 LAST PATH I68
J 2
(-973 2875);
DISPLAY 0.872340 (-973 2875);
PAINT GREEN (-973 2875);
DISPLAY INVISIBLE (-973 2875);
FORCEADD TAP..1
R 2
(-975 2975);
FORCEPROP 3 LASTPIN (-925 2975) SIG_NAME M_F_CPU1_SA_DQ<10>
J 0
(-915 2985);
DISPLAY 0.659574 (-915 2985);
PAINT MONO (-915 2985);
DISPLAY INVISIBLE (-915 2985);
FORCEPROP 1 LASTPIN (-925 2975) BN 10
J 2
(-913 2983);
DISPLAY 0.680851 (-913 2983);
PAINT GREEN (-913 2983);
FORCEPROP 2 LAST CDS_LIB standard
J 0
(-975 2975);
DISPLAY INVISIBLE (-975 2975);
FORCEPROP 1 LAST BODY_TYPE PLUMBING
J 2
(-975 3025);
DISPLAY 0.872340 (-975 3025);
PAINT GREEN (-975 3025);
DISPLAY INVISIBLE (-975 3025);
FORCEPROP 1 LAST HDL_TAP TRUE
J 2
(-1300 2850);
DISPLAY 0.872340 (-1300 2850);
DISPLAY INVISIBLE (-1300 2850);
FORCEPROP 1 LAST PATH I69
J 2
(-973 2975);
DISPLAY 0.872340 (-973 2975);
PAINT GREEN (-973 2975);
DISPLAY INVISIBLE (-973 2975);
FORCEADD TAP..1
R 2
(-975 -75);
FORCEPROP 3 LASTPIN (-925 -75) SIG_NAME M_F_CPU1_CLK_DP<0>
J 0
(-915 -65);
DISPLAY 0.659574 (-915 -65);
PAINT MONO (-915 -65);
DISPLAY INVISIBLE (-915 -65);
FORCEPROP 1 LASTPIN (-925 -75) BN 0
J 2
(-913 -67);
DISPLAY 0.680851 (-913 -67);
PAINT GREEN (-913 -67);
FORCEPROP 2 LAST CDS_LIB standard
J 0
(-975 -75);
DISPLAY INVISIBLE (-975 -75);
FORCEPROP 1 LAST BODY_TYPE PLUMBING
J 2
(-975 -25);
DISPLAY 0.872340 (-975 -25);
PAINT GREEN (-975 -25);
DISPLAY INVISIBLE (-975 -25);
FORCEPROP 1 LAST HDL_TAP TRUE
J 2
(-1300 -200);
DISPLAY 0.872340 (-1300 -200);
DISPLAY INVISIBLE (-1300 -200);
FORCEPROP 1 LAST PATH I7
J 2
(-973 -75);
DISPLAY 0.872340 (-973 -75);
PAINT GREEN (-973 -75);
DISPLAY INVISIBLE (-973 -75);
FORCEADD TAP..1
R 2
(-975 3025);
FORCEPROP 3 LASTPIN (-925 3025) SIG_NAME M_F_CPU1_SA_DQ<11>
J 0
(-915 3035);
DISPLAY 0.659574 (-915 3035);
PAINT MONO (-915 3035);
DISPLAY INVISIBLE (-915 3035);
FORCEPROP 1 LASTPIN (-925 3025) BN 11
J 2
(-913 3033);
DISPLAY 0.680851 (-913 3033);
PAINT GREEN (-913 3033);
FORCEPROP 2 LAST CDS_LIB standard
J 0
(-975 3025);
DISPLAY INVISIBLE (-975 3025);
FORCEPROP 1 LAST BODY_TYPE PLUMBING
J 2
(-975 3075);
DISPLAY 0.872340 (-975 3075);
PAINT GREEN (-975 3075);
DISPLAY INVISIBLE (-975 3075);
FORCEPROP 1 LAST HDL_TAP TRUE
J 2
(-1300 2900);
DISPLAY 0.872340 (-1300 2900);
DISPLAY INVISIBLE (-1300 2900);
FORCEPROP 1 LAST PATH I70
J 2
(-973 3025);
DISPLAY 0.872340 (-973 3025);
PAINT GREEN (-973 3025);
DISPLAY INVISIBLE (-973 3025);
FORCEADD TAP..1
R 2
(-975 3075);
FORCEPROP 3 LASTPIN (-925 3075) SIG_NAME M_F_CPU1_SA_DQ<12>
J 0
(-915 3085);
DISPLAY 0.659574 (-915 3085);
PAINT MONO (-915 3085);
DISPLAY INVISIBLE (-915 3085);
FORCEPROP 1 LASTPIN (-925 3075) BN 12
J 2
(-913 3083);
DISPLAY 0.680851 (-913 3083);
PAINT GREEN (-913 3083);
FORCEPROP 2 LAST CDS_LIB standard
J 0
(-975 3075);
DISPLAY INVISIBLE (-975 3075);
FORCEPROP 1 LAST BODY_TYPE PLUMBING
J 2
(-975 3125);
DISPLAY 0.872340 (-975 3125);
PAINT GREEN (-975 3125);
DISPLAY INVISIBLE (-975 3125);
FORCEPROP 1 LAST HDL_TAP TRUE
J 2
(-1300 2950);
DISPLAY 0.872340 (-1300 2950);
DISPLAY INVISIBLE (-1300 2950);
FORCEPROP 1 LAST PATH I71
J 2
(-973 3075);
DISPLAY 0.872340 (-973 3075);
PAINT GREEN (-973 3075);
DISPLAY INVISIBLE (-973 3075);
FORCEADD TAP..1
R 2
(-975 3175);
FORCEPROP 3 LASTPIN (-925 3175) SIG_NAME M_F_CPU1_SA_DQ<14>
J 0
(-915 3185);
DISPLAY 0.659574 (-915 3185);
PAINT MONO (-915 3185);
DISPLAY INVISIBLE (-915 3185);
FORCEPROP 1 LASTPIN (-925 3175) BN 14
J 2
(-913 3183);
DISPLAY 0.680851 (-913 3183);
PAINT GREEN (-913 3183);
FORCEPROP 2 LAST CDS_LIB standard
J 0
(-975 3175);
DISPLAY INVISIBLE (-975 3175);
FORCEPROP 1 LAST BODY_TYPE PLUMBING
J 2
(-975 3225);
DISPLAY 0.872340 (-975 3225);
PAINT GREEN (-975 3225);
DISPLAY INVISIBLE (-975 3225);
FORCEPROP 1 LAST HDL_TAP TRUE
J 2
(-1300 3050);
DISPLAY 0.872340 (-1300 3050);
DISPLAY INVISIBLE (-1300 3050);
FORCEPROP 1 LAST PATH I72
J 2
(-973 3175);
DISPLAY 0.872340 (-973 3175);
PAINT GREEN (-973 3175);
DISPLAY INVISIBLE (-973 3175);
FORCEADD TAP..1
R 2
(-975 3125);
FORCEPROP 3 LASTPIN (-925 3125) SIG_NAME M_F_CPU1_SA_DQ<13>
J 0
(-915 3135);
DISPLAY 0.659574 (-915 3135);
PAINT MONO (-915 3135);
DISPLAY INVISIBLE (-915 3135);
FORCEPROP 1 LASTPIN (-925 3125) BN 13
J 2
(-913 3133);
DISPLAY 0.680851 (-913 3133);
PAINT GREEN (-913 3133);
FORCEPROP 2 LAST CDS_LIB standard
J 0
(-975 3125);
DISPLAY INVISIBLE (-975 3125);
FORCEPROP 1 LAST BODY_TYPE PLUMBING
J 2
(-975 3175);
DISPLAY 0.872340 (-975 3175);
PAINT GREEN (-975 3175);
DISPLAY INVISIBLE (-975 3175);
FORCEPROP 1 LAST HDL_TAP TRUE
J 2
(-1300 3000);
DISPLAY 0.872340 (-1300 3000);
DISPLAY INVISIBLE (-1300 3000);
FORCEPROP 1 LAST PATH I73
J 2
(-973 3125);
DISPLAY 0.872340 (-973 3125);
PAINT GREEN (-973 3125);
DISPLAY INVISIBLE (-973 3125);
FORCEADD TAP..1
R 2
(-975 3225);
FORCEPROP 3 LASTPIN (-925 3225) SIG_NAME M_F_CPU1_SA_DQ<15>
J 0
(-915 3235);
DISPLAY 0.659574 (-915 3235);
PAINT MONO (-915 3235);
DISPLAY INVISIBLE (-915 3235);
FORCEPROP 1 LASTPIN (-925 3225) BN 15
J 2
(-913 3233);
DISPLAY 0.680851 (-913 3233);
PAINT GREEN (-913 3233);
FORCEPROP 2 LAST CDS_LIB standard
J 0
(-975 3225);
DISPLAY INVISIBLE (-975 3225);
FORCEPROP 1 LAST BODY_TYPE PLUMBING
J 2
(-975 3275);
DISPLAY 0.872340 (-975 3275);
PAINT GREEN (-975 3275);
DISPLAY INVISIBLE (-975 3275);
FORCEPROP 1 LAST HDL_TAP TRUE
J 2
(-1300 3100);
DISPLAY 0.872340 (-1300 3100);
DISPLAY INVISIBLE (-1300 3100);
FORCEPROP 1 LAST PATH I74
J 2
(-973 3225);
DISPLAY 0.872340 (-973 3225);
PAINT GREEN (-973 3225);
DISPLAY INVISIBLE (-973 3225);
FORCEADD TAP..1
R 2
(-975 3275);
FORCEPROP 3 LASTPIN (-925 3275) SIG_NAME M_F_CPU1_SA_DQ<16>
J 0
(-915 3285);
DISPLAY 0.659574 (-915 3285);
PAINT MONO (-915 3285);
DISPLAY INVISIBLE (-915 3285);
FORCEPROP 1 LASTPIN (-925 3275) BN 16
J 2
(-913 3283);
DISPLAY 0.680851 (-913 3283);
PAINT GREEN (-913 3283);
FORCEPROP 2 LAST CDS_LIB standard
J 0
(-975 3275);
DISPLAY INVISIBLE (-975 3275);
FORCEPROP 1 LAST BODY_TYPE PLUMBING
J 2
(-975 3325);
DISPLAY 0.872340 (-975 3325);
PAINT GREEN (-975 3325);
DISPLAY INVISIBLE (-975 3325);
FORCEPROP 1 LAST HDL_TAP TRUE
J 2
(-1300 3150);
DISPLAY 0.872340 (-1300 3150);
DISPLAY INVISIBLE (-1300 3150);
FORCEPROP 1 LAST PATH I75
J 2
(-973 3275);
DISPLAY 0.872340 (-973 3275);
PAINT GREEN (-973 3275);
DISPLAY INVISIBLE (-973 3275);
FORCEADD TAP..1
R 2
(-975 3325);
FORCEPROP 3 LASTPIN (-925 3325) SIG_NAME M_F_CPU1_SA_DQ<17>
J 0
(-915 3335);
DISPLAY 0.659574 (-915 3335);
PAINT MONO (-915 3335);
DISPLAY INVISIBLE (-915 3335);
FORCEPROP 1 LASTPIN (-925 3325) BN 17
J 2
(-913 3333);
DISPLAY 0.680851 (-913 3333);
PAINT GREEN (-913 3333);
FORCEPROP 2 LAST CDS_LIB standard
J 0
(-975 3325);
DISPLAY INVISIBLE (-975 3325);
FORCEPROP 1 LAST BODY_TYPE PLUMBING
J 2
(-975 3375);
DISPLAY 0.872340 (-975 3375);
PAINT GREEN (-975 3375);
DISPLAY INVISIBLE (-975 3375);
FORCEPROP 1 LAST HDL_TAP TRUE
J 2
(-1300 3200);
DISPLAY 0.872340 (-1300 3200);
DISPLAY INVISIBLE (-1300 3200);
FORCEPROP 1 LAST PATH I76
J 2
(-973 3325);
DISPLAY 0.872340 (-973 3325);
PAINT GREEN (-973 3325);
DISPLAY INVISIBLE (-973 3325);
FORCEADD TAP..1
R 2
(-975 3425);
FORCEPROP 3 LASTPIN (-925 3425) SIG_NAME M_F_CPU1_SA_DQ<19>
J 0
(-915 3435);
DISPLAY 0.659574 (-915 3435);
PAINT MONO (-915 3435);
DISPLAY INVISIBLE (-915 3435);
FORCEPROP 1 LASTPIN (-925 3425) BN 19
J 2
(-913 3433);
DISPLAY 0.680851 (-913 3433);
PAINT GREEN (-913 3433);
FORCEPROP 2 LAST CDS_LIB standard
J 0
(-975 3425);
DISPLAY INVISIBLE (-975 3425);
FORCEPROP 1 LAST BODY_TYPE PLUMBING
J 2
(-975 3475);
DISPLAY 0.872340 (-975 3475);
PAINT GREEN (-975 3475);
DISPLAY INVISIBLE (-975 3475);
FORCEPROP 1 LAST HDL_TAP TRUE
J 2
(-1300 3300);
DISPLAY 0.872340 (-1300 3300);
DISPLAY INVISIBLE (-1300 3300);
FORCEPROP 1 LAST PATH I77
J 2
(-973 3425);
DISPLAY 0.872340 (-973 3425);
PAINT GREEN (-973 3425);
DISPLAY INVISIBLE (-973 3425);
FORCEADD TAP..1
R 2
(-975 3475);
FORCEPROP 3 LASTPIN (-925 3475) SIG_NAME M_F_CPU1_SA_DQ<20>
J 0
(-915 3485);
DISPLAY 0.659574 (-915 3485);
PAINT MONO (-915 3485);
DISPLAY INVISIBLE (-915 3485);
FORCEPROP 1 LASTPIN (-925 3475) BN 20
J 2
(-913 3483);
DISPLAY 0.680851 (-913 3483);
PAINT GREEN (-913 3483);
FORCEPROP 2 LAST CDS_LIB standard
J 0
(-975 3475);
DISPLAY INVISIBLE (-975 3475);
FORCEPROP 1 LAST BODY_TYPE PLUMBING
J 2
(-975 3525);
DISPLAY 0.872340 (-975 3525);
PAINT GREEN (-975 3525);
DISPLAY INVISIBLE (-975 3525);
FORCEPROP 1 LAST HDL_TAP TRUE
J 2
(-1300 3350);
DISPLAY 0.872340 (-1300 3350);
DISPLAY INVISIBLE (-1300 3350);
FORCEPROP 1 LAST PATH I78
J 2
(-973 3475);
DISPLAY 0.872340 (-973 3475);
PAINT GREEN (-973 3475);
DISPLAY INVISIBLE (-973 3475);
FORCEADD TAP..1
R 2
(-975 3375);
FORCEPROP 3 LASTPIN (-925 3375) SIG_NAME M_F_CPU1_SA_DQ<18>
J 0
(-915 3385);
DISPLAY 0.659574 (-915 3385);
PAINT MONO (-915 3385);
DISPLAY INVISIBLE (-915 3385);
FORCEPROP 1 LASTPIN (-925 3375) BN 18
J 2
(-913 3383);
DISPLAY 0.680851 (-913 3383);
PAINT GREEN (-913 3383);
FORCEPROP 2 LAST CDS_LIB standard
J 0
(-975 3375);
DISPLAY INVISIBLE (-975 3375);
FORCEPROP 1 LAST BODY_TYPE PLUMBING
J 2
(-975 3425);
DISPLAY 0.872340 (-975 3425);
PAINT GREEN (-975 3425);
DISPLAY INVISIBLE (-975 3425);
FORCEPROP 1 LAST HDL_TAP TRUE
J 2
(-1300 3250);
DISPLAY 0.872340 (-1300 3250);
DISPLAY INVISIBLE (-1300 3250);
FORCEPROP 1 LAST PATH I79
J 2
(-973 3375);
DISPLAY 0.872340 (-973 3375);
PAINT GREEN (-973 3375);
DISPLAY INVISIBLE (-973 3375);
FORCEADD TAP..1
R 2
(-975 -25);
FORCEPROP 3 LASTPIN (-925 -25) SIG_NAME M_F_CPU1_CLK_DP<1>
J 0
(-915 -15);
DISPLAY 0.659574 (-915 -15);
PAINT MONO (-915 -15);
DISPLAY INVISIBLE (-915 -15);
FORCEPROP 1 LASTPIN (-925 -25) BN 1
J 2
(-913 -17);
DISPLAY 0.680851 (-913 -17);
PAINT GREEN (-913 -17);
FORCEPROP 2 LAST CDS_LIB standard
J 0
(-975 -25);
DISPLAY INVISIBLE (-975 -25);
FORCEPROP 1 LAST BODY_TYPE PLUMBING
J 2
(-975 25);
DISPLAY 0.872340 (-975 25);
PAINT GREEN (-975 25);
DISPLAY INVISIBLE (-975 25);
FORCEPROP 1 LAST HDL_TAP TRUE
J 2
(-1300 -150);
DISPLAY 0.872340 (-1300 -150);
DISPLAY INVISIBLE (-1300 -150);
FORCEPROP 1 LAST PATH I8
J 2
(-973 -25);
DISPLAY 0.872340 (-973 -25);
PAINT GREEN (-973 -25);
DISPLAY INVISIBLE (-973 -25);
FORCEADD TAP..1
R 2
(-975 3575);
FORCEPROP 3 LASTPIN (-925 3575) SIG_NAME M_F_CPU1_SA_DQ<22>
J 0
(-915 3585);
DISPLAY 0.659574 (-915 3585);
PAINT MONO (-915 3585);
DISPLAY INVISIBLE (-915 3585);
FORCEPROP 1 LASTPIN (-925 3575) BN 22
J 2
(-913 3583);
DISPLAY 0.680851 (-913 3583);
PAINT GREEN (-913 3583);
FORCEPROP 2 LAST CDS_LIB standard
J 0
(-975 3575);
DISPLAY INVISIBLE (-975 3575);
FORCEPROP 1 LAST BODY_TYPE PLUMBING
J 2
(-975 3625);
DISPLAY 0.872340 (-975 3625);
PAINT GREEN (-975 3625);
DISPLAY INVISIBLE (-975 3625);
FORCEPROP 1 LAST HDL_TAP TRUE
J 2
(-1300 3450);
DISPLAY 0.872340 (-1300 3450);
DISPLAY INVISIBLE (-1300 3450);
FORCEPROP 1 LAST PATH I80
J 2
(-973 3575);
DISPLAY 0.872340 (-973 3575);
PAINT GREEN (-973 3575);
DISPLAY INVISIBLE (-973 3575);
FORCEADD TAP..1
R 2
(-975 3525);
FORCEPROP 3 LASTPIN (-925 3525) SIG_NAME M_F_CPU1_SA_DQ<21>
J 0
(-915 3535);
DISPLAY 0.659574 (-915 3535);
PAINT MONO (-915 3535);
DISPLAY INVISIBLE (-915 3535);
FORCEPROP 1 LASTPIN (-925 3525) BN 21
J 2
(-913 3533);
DISPLAY 0.680851 (-913 3533);
PAINT GREEN (-913 3533);
FORCEPROP 2 LAST CDS_LIB standard
J 0
(-975 3525);
DISPLAY INVISIBLE (-975 3525);
FORCEPROP 1 LAST BODY_TYPE PLUMBING
J 2
(-975 3575);
DISPLAY 0.872340 (-975 3575);
PAINT GREEN (-975 3575);
DISPLAY INVISIBLE (-975 3575);
FORCEPROP 1 LAST HDL_TAP TRUE
J 2
(-1300 3400);
DISPLAY 0.872340 (-1300 3400);
DISPLAY INVISIBLE (-1300 3400);
FORCEPROP 1 LAST PATH I81
J 2
(-973 3525);
DISPLAY 0.872340 (-973 3525);
PAINT GREEN (-973 3525);
DISPLAY INVISIBLE (-973 3525);
FORCEADD TAP..1
R 2
(-975 3675);
FORCEPROP 3 LASTPIN (-925 3675) SIG_NAME M_F_CPU1_SA_DQ<24>
J 0
(-915 3685);
DISPLAY 0.659574 (-915 3685);
PAINT MONO (-915 3685);
DISPLAY INVISIBLE (-915 3685);
FORCEPROP 1 LASTPIN (-925 3675) BN 24
J 2
(-913 3683);
DISPLAY 0.680851 (-913 3683);
PAINT GREEN (-913 3683);
FORCEPROP 2 LAST CDS_LIB standard
J 0
(-975 3675);
DISPLAY INVISIBLE (-975 3675);
FORCEPROP 1 LAST BODY_TYPE PLUMBING
J 2
(-975 3725);
DISPLAY 0.872340 (-975 3725);
PAINT GREEN (-975 3725);
DISPLAY INVISIBLE (-975 3725);
FORCEPROP 1 LAST HDL_TAP TRUE
J 2
(-1300 3550);
DISPLAY 0.872340 (-1300 3550);
DISPLAY INVISIBLE (-1300 3550);
FORCEPROP 1 LAST PATH I82
J 2
(-973 3675);
DISPLAY 0.872340 (-973 3675);
PAINT GREEN (-973 3675);
DISPLAY INVISIBLE (-973 3675);
FORCEADD TAP..1
R 2
(-975 3625);
FORCEPROP 3 LASTPIN (-925 3625) SIG_NAME M_F_CPU1_SA_DQ<23>
J 0
(-915 3635);
DISPLAY 0.659574 (-915 3635);
PAINT MONO (-915 3635);
DISPLAY INVISIBLE (-915 3635);
FORCEPROP 1 LASTPIN (-925 3625) BN 23
J 2
(-913 3633);
DISPLAY 0.680851 (-913 3633);
PAINT GREEN (-913 3633);
FORCEPROP 2 LAST CDS_LIB standard
J 0
(-975 3625);
DISPLAY INVISIBLE (-975 3625);
FORCEPROP 1 LAST BODY_TYPE PLUMBING
J 2
(-975 3675);
DISPLAY 0.872340 (-975 3675);
PAINT GREEN (-975 3675);
DISPLAY INVISIBLE (-975 3675);
FORCEPROP 1 LAST HDL_TAP TRUE
J 2
(-1300 3500);
DISPLAY 0.872340 (-1300 3500);
DISPLAY INVISIBLE (-1300 3500);
FORCEPROP 1 LAST PATH I83
J 2
(-973 3625);
DISPLAY 0.872340 (-973 3625);
PAINT GREEN (-973 3625);
DISPLAY INVISIBLE (-973 3625);
FORCEADD TAP..1
R 2
(-975 3725);
FORCEPROP 3 LASTPIN (-925 3725) SIG_NAME M_F_CPU1_SA_DQ<25>
J 0
(-915 3735);
DISPLAY 0.659574 (-915 3735);
PAINT MONO (-915 3735);
DISPLAY INVISIBLE (-915 3735);
FORCEPROP 1 LASTPIN (-925 3725) BN 25
J 2
(-913 3733);
DISPLAY 0.680851 (-913 3733);
PAINT GREEN (-913 3733);
FORCEPROP 2 LAST CDS_LIB standard
J 0
(-975 3725);
DISPLAY INVISIBLE (-975 3725);
FORCEPROP 1 LAST BODY_TYPE PLUMBING
J 2
(-975 3775);
DISPLAY 0.872340 (-975 3775);
PAINT GREEN (-975 3775);
DISPLAY INVISIBLE (-975 3775);
FORCEPROP 1 LAST HDL_TAP TRUE
J 2
(-1300 3600);
DISPLAY 0.872340 (-1300 3600);
DISPLAY INVISIBLE (-1300 3600);
FORCEPROP 1 LAST PATH I84
J 2
(-973 3725);
DISPLAY 0.872340 (-973 3725);
PAINT GREEN (-973 3725);
DISPLAY INVISIBLE (-973 3725);
FORCEADD TAP..1
R 2
(-975 3825);
FORCEPROP 3 LASTPIN (-925 3825) SIG_NAME M_F_CPU1_SA_DQ<27>
J 0
(-915 3835);
DISPLAY 0.659574 (-915 3835);
PAINT MONO (-915 3835);
DISPLAY INVISIBLE (-915 3835);
FORCEPROP 1 LASTPIN (-925 3825) BN 27
J 2
(-913 3833);
DISPLAY 0.680851 (-913 3833);
PAINT GREEN (-913 3833);
FORCEPROP 2 LAST CDS_LIB standard
J 0
(-975 3825);
DISPLAY INVISIBLE (-975 3825);
FORCEPROP 1 LAST BODY_TYPE PLUMBING
J 2
(-975 3875);
DISPLAY 0.872340 (-975 3875);
PAINT GREEN (-975 3875);
DISPLAY INVISIBLE (-975 3875);
FORCEPROP 1 LAST HDL_TAP TRUE
J 2
(-1300 3700);
DISPLAY 0.872340 (-1300 3700);
DISPLAY INVISIBLE (-1300 3700);
FORCEPROP 1 LAST PATH I85
J 2
(-973 3825);
DISPLAY 0.872340 (-973 3825);
PAINT GREEN (-973 3825);
DISPLAY INVISIBLE (-973 3825);
FORCEADD TAP..1
R 2
(-975 3775);
FORCEPROP 3 LASTPIN (-925 3775) SIG_NAME M_F_CPU1_SA_DQ<26>
J 0
(-915 3785);
DISPLAY 0.659574 (-915 3785);
PAINT MONO (-915 3785);
DISPLAY INVISIBLE (-915 3785);
FORCEPROP 1 LASTPIN (-925 3775) BN 26
J 2
(-913 3783);
DISPLAY 0.680851 (-913 3783);
PAINT GREEN (-913 3783);
FORCEPROP 2 LAST CDS_LIB standard
J 0
(-975 3775);
DISPLAY INVISIBLE (-975 3775);
FORCEPROP 1 LAST BODY_TYPE PLUMBING
J 2
(-975 3825);
DISPLAY 0.872340 (-975 3825);
PAINT GREEN (-975 3825);
DISPLAY INVISIBLE (-975 3825);
FORCEPROP 1 LAST HDL_TAP TRUE
J 2
(-1300 3650);
DISPLAY 0.872340 (-1300 3650);
DISPLAY INVISIBLE (-1300 3650);
FORCEPROP 1 LAST PATH I86
J 2
(-973 3775);
DISPLAY 0.872340 (-973 3775);
PAINT GREEN (-973 3775);
DISPLAY INVISIBLE (-973 3775);
FORCEADD TAP..1
R 2
(-975 3875);
FORCEPROP 3 LASTPIN (-925 3875) SIG_NAME M_F_CPU1_SA_DQ<28>
J 0
(-915 3885);
DISPLAY 0.659574 (-915 3885);
PAINT MONO (-915 3885);
DISPLAY INVISIBLE (-915 3885);
FORCEPROP 1 LASTPIN (-925 3875) BN 28
J 2
(-913 3883);
DISPLAY 0.680851 (-913 3883);
PAINT GREEN (-913 3883);
FORCEPROP 2 LAST CDS_LIB standard
J 0
(-975 3875);
DISPLAY INVISIBLE (-975 3875);
FORCEPROP 1 LAST BODY_TYPE PLUMBING
J 2
(-975 3925);
DISPLAY 0.872340 (-975 3925);
PAINT GREEN (-975 3925);
DISPLAY INVISIBLE (-975 3925);
FORCEPROP 1 LAST HDL_TAP TRUE
J 2
(-1300 3750);
DISPLAY 0.872340 (-1300 3750);
DISPLAY INVISIBLE (-1300 3750);
FORCEPROP 1 LAST PATH I87
J 2
(-973 3875);
DISPLAY 0.872340 (-973 3875);
PAINT GREEN (-973 3875);
DISPLAY INVISIBLE (-973 3875);
FORCEADD TAP..1
R 2
(-975 3925);
FORCEPROP 3 LASTPIN (-925 3925) SIG_NAME M_F_CPU1_SA_DQ<29>
J 0
(-915 3935);
DISPLAY 0.659574 (-915 3935);
PAINT MONO (-915 3935);
DISPLAY INVISIBLE (-915 3935);
FORCEPROP 1 LASTPIN (-925 3925) BN 29
J 2
(-913 3933);
DISPLAY 0.680851 (-913 3933);
PAINT GREEN (-913 3933);
FORCEPROP 2 LAST CDS_LIB standard
J 0
(-975 3925);
DISPLAY INVISIBLE (-975 3925);
FORCEPROP 1 LAST BODY_TYPE PLUMBING
J 2
(-975 3975);
DISPLAY 0.872340 (-975 3975);
PAINT GREEN (-975 3975);
DISPLAY INVISIBLE (-975 3975);
FORCEPROP 1 LAST HDL_TAP TRUE
J 2
(-1300 3800);
DISPLAY 0.872340 (-1300 3800);
DISPLAY INVISIBLE (-1300 3800);
FORCEPROP 1 LAST PATH I88
J 2
(-973 3925);
DISPLAY 0.872340 (-973 3925);
PAINT GREEN (-973 3925);
DISPLAY INVISIBLE (-973 3925);
FORCEADD TAP..1
R 2
(-975 3975);
FORCEPROP 3 LASTPIN (-925 3975) SIG_NAME M_F_CPU1_SA_DQ<30>
J 0
(-915 3985);
DISPLAY 0.659574 (-915 3985);
PAINT MONO (-915 3985);
DISPLAY INVISIBLE (-915 3985);
FORCEPROP 1 LASTPIN (-925 3975) BN 30
J 2
(-913 3983);
DISPLAY 0.680851 (-913 3983);
PAINT GREEN (-913 3983);
FORCEPROP 2 LAST CDS_LIB standard
J 0
(-975 3975);
DISPLAY INVISIBLE (-975 3975);
FORCEPROP 1 LAST BODY_TYPE PLUMBING
J 2
(-975 4025);
DISPLAY 0.872340 (-975 4025);
PAINT GREEN (-975 4025);
DISPLAY INVISIBLE (-975 4025);
FORCEPROP 1 LAST HDL_TAP TRUE
J 2
(-1300 3850);
DISPLAY 0.872340 (-1300 3850);
DISPLAY INVISIBLE (-1300 3850);
FORCEPROP 1 LAST PATH I89
J 2
(-973 3975);
DISPLAY 0.872340 (-973 3975);
PAINT GREEN (-973 3975);
DISPLAY INVISIBLE (-973 3975);
FORCEADD TAP..1
R 2
(-975 175);
FORCEPROP 3 LASTPIN (-925 175) SIG_NAME M_F_CPU1_SB_CB<2>
J 0
(-915 185);
DISPLAY 0.659574 (-915 185);
PAINT MONO (-915 185);
DISPLAY INVISIBLE (-915 185);
FORCEPROP 1 LASTPIN (-925 175) BN 2
J 2
(-913 183);
DISPLAY 0.680851 (-913 183);
PAINT GREEN (-913 183);
FORCEPROP 2 LAST CDS_LIB standard
J 0
(-975 175);
DISPLAY INVISIBLE (-975 175);
FORCEPROP 1 LAST BODY_TYPE PLUMBING
J 2
(-975 225);
DISPLAY 0.872340 (-975 225);
PAINT GREEN (-975 225);
DISPLAY INVISIBLE (-975 225);
FORCEPROP 1 LAST HDL_TAP TRUE
J 2
(-1300 50);
DISPLAY 0.872340 (-1300 50);
DISPLAY INVISIBLE (-1300 50);
FORCEPROP 1 LAST PATH I9
J 2
(-973 175);
DISPLAY 0.872340 (-973 175);
PAINT GREEN (-973 175);
DISPLAY INVISIBLE (-973 175);
FORCEADD TAP..1
R 2
(-975 4025);
FORCEPROP 3 LASTPIN (-925 4025) SIG_NAME M_F_CPU1_SA_DQ<31>
J 0
(-915 4035);
DISPLAY 0.659574 (-915 4035);
PAINT MONO (-915 4035);
DISPLAY INVISIBLE (-915 4035);
FORCEPROP 1 LASTPIN (-925 4025) BN 31
J 2
(-913 4033);
DISPLAY 0.680851 (-913 4033);
PAINT GREEN (-913 4033);
FORCEPROP 2 LAST CDS_LIB standard
J 0
(-975 4025);
DISPLAY INVISIBLE (-975 4025);
FORCEPROP 1 LAST BODY_TYPE PLUMBING
J 2
(-975 4075);
DISPLAY 0.872340 (-975 4075);
PAINT GREEN (-975 4075);
DISPLAY INVISIBLE (-975 4075);
FORCEPROP 1 LAST HDL_TAP TRUE
J 2
(-1300 3900);
DISPLAY 0.872340 (-1300 3900);
DISPLAY INVISIBLE (-1300 3900);
FORCEPROP 1 LAST PATH I90
J 2
(-973 4025);
DISPLAY 0.872340 (-973 4025);
PAINT GREEN (-973 4025);
DISPLAY INVISIBLE (-973 4025);
FORCEADD OFFPAGE..4
(3550 -175);
FORCEPROP 2 LAST $XR1 109 
J 0
(3856 -175);
DISPLAY 0.638298 (3856 -175);
PAINT MONO (3856 -175);
FORCEPROP 2 LAST $XR0 108 
J 0
(3736 -175);
DISPLAY 0.638298 (3736 -175);
PAINT MONO (3736 -175);
FORCEPROP 2 LAST CDS_LIB standard
J 0
(3550 -175);
PAINT MONO (3550 -175);
DISPLAY INVISIBLE (3550 -175);
FORCEPROP 1 LAST OFFPAGE TRUE
J 0
(3875 -300);
DISPLAY 1.170213 (3875 -300);
PAINT GREEN (3875 -300);
DISPLAY INVISIBLE (3875 -300);
FORCEPROP 1 LAST COMMENT_BODY TRUE
J 0
(3525 -275);
DISPLAY 1.170213 (3525 -275);
PAINT GREEN (3525 -275);
DISPLAY INVISIBLE (3525 -275);
FORCEPROP 2 LAST PATH I91
J 0
(3725 -100);
DISPLAY 1.021277 (3725 -100);
DISPLAY INVISIBLE (3725 -100);
FORCEADD OFFPAGE..4
(3550 -75);
FORCEPROP 2 LAST $XR0 108 
J 0
(3736 -75);
DISPLAY 0.638298 (3736 -75);
PAINT MONO (3736 -75);
FORCEPROP 2 LAST CDS_LIB standard
J 0
(3550 -75);
PAINT MONO (3550 -75);
DISPLAY INVISIBLE (3550 -75);
FORCEPROP 1 LAST OFFPAGE TRUE
J 0
(3875 -200);
DISPLAY 1.170213 (3875 -200);
PAINT GREEN (3875 -200);
DISPLAY INVISIBLE (3875 -200);
FORCEPROP 1 LAST COMMENT_BODY TRUE
J 0
(3525 -175);
DISPLAY 1.170213 (3525 -175);
PAINT GREEN (3525 -175);
DISPLAY INVISIBLE (3525 -175);
FORCEPROP 2 LAST PATH I92
J 0
(3725 0);
DISPLAY 1.021277 (3725 0);
DISPLAY INVISIBLE (3725 0);
FORCEADD OFFPAGE..4
(3550 -25);
FORCEPROP 2 LAST $XR0 109 
J 0
(3736 -25);
DISPLAY 0.638298 (3736 -25);
PAINT MONO (3736 -25);
FORCEPROP 2 LAST CDS_LIB standard
J 0
(3550 -25);
PAINT MONO (3550 -25);
DISPLAY INVISIBLE (3550 -25);
FORCEPROP 1 LAST OFFPAGE TRUE
J 0
(3875 -150);
DISPLAY 1.170213 (3875 -150);
PAINT GREEN (3875 -150);
DISPLAY INVISIBLE (3875 -150);
FORCEPROP 1 LAST COMMENT_BODY TRUE
J 0
(3525 -125);
DISPLAY 1.170213 (3525 -125);
PAINT GREEN (3525 -125);
DISPLAY INVISIBLE (3525 -125);
FORCEPROP 2 LAST PATH I93
J 0
(3725 50);
DISPLAY 1.021277 (3725 50);
DISPLAY INVISIBLE (3725 50);
FORCEADD OFFPAGE..4
(3550 75);
FORCEPROP 2 LAST $XR0 108 
J 0
(3736 75);
DISPLAY 0.638298 (3736 75);
PAINT MONO (3736 75);
FORCEPROP 2 LAST CDS_LIB standard
J 0
(3550 75);
PAINT MONO (3550 75);
DISPLAY INVISIBLE (3550 75);
FORCEPROP 1 LAST OFFPAGE TRUE
J 0
(3875 -50);
DISPLAY 1.170213 (3875 -50);
PAINT GREEN (3875 -50);
DISPLAY INVISIBLE (3875 -50);
FORCEPROP 1 LAST COMMENT_BODY TRUE
J 0
(3525 -25);
DISPLAY 1.170213 (3525 -25);
PAINT GREEN (3525 -25);
DISPLAY INVISIBLE (3525 -25);
FORCEPROP 2 LAST PATH I94
J 0
(3725 150);
DISPLAY 1.021277 (3725 150);
DISPLAY INVISIBLE (3725 150);
FORCEADD OFFPAGE..4
(3550 125);
FORCEPROP 2 LAST $XR0 109 
J 0
(3736 125);
DISPLAY 0.638298 (3736 125);
PAINT MONO (3736 125);
FORCEPROP 2 LAST CDS_LIB standard
J 0
(3550 125);
PAINT MONO (3550 125);
DISPLAY INVISIBLE (3550 125);
FORCEPROP 1 LAST OFFPAGE TRUE
J 0
(3875 0);
DISPLAY 1.170213 (3875 0);
PAINT GREEN (3875 0);
DISPLAY INVISIBLE (3875 0);
FORCEPROP 1 LAST COMMENT_BODY TRUE
J 0
(3525 25);
DISPLAY 1.170213 (3525 25);
PAINT GREEN (3525 25);
DISPLAY INVISIBLE (3525 25);
FORCEPROP 2 LAST PATH I95
J 0
(3725 200);
DISPLAY 1.021277 (3725 200);
DISPLAY INVISIBLE (3725 200);
FORCEADD TAP..1
(2450 275);
FORCEPROP 3 LASTPIN (2400 275) SIG_NAME M_F_CPU1_SB_CS_N<0>
J 0
(2410 285);
DISPLAY 0.659574 (2410 285);
PAINT MONO (2410 285);
DISPLAY INVISIBLE (2410 285);
FORCEPROP 1 LASTPIN (2400 275) BN 0
J 0
(2388 283);
DISPLAY 0.680851 (2388 283);
PAINT GREEN (2388 283);
FORCEPROP 2 LAST CDS_LIB standard
J 0
(2450 275);
DISPLAY INVISIBLE (2450 275);
FORCEPROP 1 LAST BODY_TYPE PLUMBING
J 0
(2450 325);
DISPLAY 0.872340 (2450 325);
PAINT GREEN (2450 325);
DISPLAY INVISIBLE (2450 325);
FORCEPROP 1 LAST HDL_TAP TRUE
J 0
(2775 150);
DISPLAY 0.872340 (2775 150);
DISPLAY INVISIBLE (2775 150);
FORCEPROP 1 LAST PATH I96
J 0
(2448 275);
DISPLAY 0.872340 (2448 275);
PAINT GREEN (2448 275);
DISPLAY INVISIBLE (2448 275);
FORCEADD TAP..1
(2450 425);
FORCEPROP 3 LASTPIN (2400 425) SIG_NAME M_F_CPU1_SB_CS_N<3>
J 0
(2410 435);
DISPLAY 0.659574 (2410 435);
PAINT MONO (2410 435);
DISPLAY INVISIBLE (2410 435);
FORCEPROP 1 LASTPIN (2400 425) BN 3
J 0
(2388 433);
DISPLAY 0.680851 (2388 433);
PAINT GREEN (2388 433);
FORCEPROP 2 LAST CDS_LIB standard
J 0
(2450 425);
DISPLAY INVISIBLE (2450 425);
FORCEPROP 1 LAST BODY_TYPE PLUMBING
J 0
(2450 475);
DISPLAY 0.872340 (2450 475);
PAINT GREEN (2450 475);
DISPLAY INVISIBLE (2450 475);
FORCEPROP 1 LAST HDL_TAP TRUE
J 0
(2775 300);
DISPLAY 0.872340 (2775 300);
DISPLAY INVISIBLE (2775 300);
FORCEPROP 1 LAST PATH I97
J 0
(2448 425);
DISPLAY 0.872340 (2448 425);
PAINT GREEN (2448 425);
DISPLAY INVISIBLE (2448 425);
FORCEADD TAP..1
(2450 325);
FORCEPROP 3 LASTPIN (2400 325) SIG_NAME M_F_CPU1_SB_CS_N<1>
J 0
(2410 335);
DISPLAY 0.659574 (2410 335);
PAINT MONO (2410 335);
DISPLAY INVISIBLE (2410 335);
FORCEPROP 1 LASTPIN (2400 325) BN 1
J 0
(2388 333);
DISPLAY 0.680851 (2388 333);
PAINT GREEN (2388 333);
FORCEPROP 2 LAST CDS_LIB standard
J 0
(2450 325);
DISPLAY INVISIBLE (2450 325);
FORCEPROP 1 LAST BODY_TYPE PLUMBING
J 0
(2450 375);
DISPLAY 0.872340 (2450 375);
PAINT GREEN (2450 375);
DISPLAY INVISIBLE (2450 375);
FORCEPROP 1 LAST HDL_TAP TRUE
J 0
(2775 200);
DISPLAY 0.872340 (2775 200);
DISPLAY INVISIBLE (2775 200);
FORCEPROP 1 LAST PATH I98
J 0
(2448 325);
DISPLAY 0.872340 (2448 325);
PAINT GREEN (2448 325);
DISPLAY INVISIBLE (2448 325);
FORCEADD TAP..1
(2450 375);
FORCEPROP 3 LASTPIN (2400 375) SIG_NAME M_F_CPU1_SB_CS_N<2>
J 0
(2410 385);
DISPLAY 0.659574 (2410 385);
PAINT MONO (2410 385);
DISPLAY INVISIBLE (2410 385);
FORCEPROP 1 LASTPIN (2400 375) BN 2
J 0
(2388 383);
DISPLAY 0.680851 (2388 383);
PAINT GREEN (2388 383);
FORCEPROP 2 LAST CDS_LIB standard
J 0
(2450 375);
DISPLAY INVISIBLE (2450 375);
FORCEPROP 1 LAST BODY_TYPE PLUMBING
J 0
(2450 425);
DISPLAY 0.872340 (2450 425);
PAINT GREEN (2450 425);
DISPLAY INVISIBLE (2450 425);
FORCEPROP 1 LAST HDL_TAP TRUE
J 0
(2775 250);
DISPLAY 0.872340 (2775 250);
DISPLAY INVISIBLE (2775 250);
FORCEPROP 1 LAST PATH I99
J 0
(2448 375);
DISPLAY 0.872340 (2448 375);
PAINT GREEN (2448 375);
DISPLAY INVISIBLE (2448 375);
FORCEADD QUANTA_TITLE_BLOCK_C..1
(5375 -1475);
FORCEPROP 0 LAST CDS_CON_LAST_MODIFIED Fri Aug 25 14:00:38 2023
J 0
(3490 -1460);
PAINT MONO (3490 -1460);
DISPLAY INVISIBLE (3490 -1460);
FORCEPROP 1 LAST CUSTOM_TXT_CDS <CON_LAST_MODIFIED>
J 0
(3490 -1460);
DISPLAY 0.978723 (3490 -1460);
FORCEPROP 2 LAST CUSTOM_TXT_CDS <XR_PAGE_TITLE>
J 0
(-2515 3775);
DISPLAY 0.638298 (-2515 3775);
PAINT PINK (-2515 3775);
DISPLAY INVISIBLE (-2515 3775);
FORCEPROP 2 LAST CUSTOM_TXT_CDS <Q_NUMBER>
J 0
(3972 -1372);
DISPLAY 1.212766 (3972 -1372);
FORCEPROP 1 LAST CUSTOM_TXT_CDS <NAME_2>
J 0
(2200 -1425);
FORCEPROP 1 LAST CUSTOM_TXT_CDS <NAME_1>
J 0
(2200 -1300);
FORCEPROP 1 LAST CUSTOM_TXT_CDS <Q_PROJ>
J 0
(2993 -1373);
DISPLAY 1.212766 (2993 -1373);
FORCEPROP 1 LAST CUSTOM_TXT_CDS <Q_REV>
J 0
(5191 -1372);
DISPLAY 1.212766 (5191 -1372);
FORCEPROP 1 LAST CUSTOM_TXT_CDS <CON_PAGE_NUM> OF <CON_TOTAL_PAGES>
J 0
(4929 -1457);
DISPLAY 0.978723 (4929 -1457);
FORCEPROP 1 LAST Q_TITLE SPR CPU1 - DDR CH F (13 OF 30)
J 0
(-3991 -1449);
DISPLAY 1.957447 (-3991 -1449);
PAINT GREEN (-3991 -1449);
FORCEPROP 1 LAST Q_DEPT 
J 1
(1612 -1426);
DISPLAY 1.957447 (1612 -1426);
PAINT GREEN (1612 -1426);
FORCEPROP 1 LAST COMMENT_BODY TRUE
J 0
(5387 -1488);
DISPLAY 0.978723 (5387 -1488);
PAINT GREEN (5387 -1488);
DISPLAY INVISIBLE (5387 -1488);
FORCEPROP 2 LAST CDS_XR_PAGE_TITLE CR-56 : @S9S_MB_2U_LIB.S9S_MB_2U(SCH_1):PAGE56
J 0
(-2515 3775);
DISPLAY 0.638298 (-2515 3775);
PAINT PINK (-2515 3775);
DISPLAY INVISIBLE (-2515 3775);
FORCEPROP 2 LAST CDS_LIB pure_quanta
J 0
(5375 -1475);
PAINT MONO (5375 -1475);
DISPLAY INVISIBLE (5375 -1475);
FORCEPROP 1 LAST CDS_LMAN_SYM_OUTLINE -9475,6775,100,-125
J 0
(5375 -1475);
DISPLAY 0.468085 (5375 -1475);
PAINT GREEN (5375 -1475);
DISPLAY INVISIBLE (5375 -1475);
FORCEPROP 2 LAST PAGE_BORDER TRUE
J 0
(-2515 3775);
DISPLAY 0.638298 (-2515 3775);
PAINT PINK (-2515 3775);
DISPLAY INVISIBLE (-2515 3775);
WIRE 17 -1 (2500 1750)(3500 1750);
FORCEPROP 2 LAST SIG_NAME M_F_CPU1_SA_CA<6:0>
J 0
(2640 1760);
DISPLAY 0.680851 (2640 1760);
PAINT WHITE (2640 1760);
WIRE 17 -1 (2500 1700)(2500 1750);
WIRE 17 -1 (2500 1650)(2500 1700);
WIRE 17 -1 (2500 1600)(2500 1650);
WIRE 17 -1 (2500 1550)(2500 1600);
WIRE 17 -1 (2500 1500)(2500 1550);
WIRE 17 -1 (2500 1450)(2500 1500);
WIRE 17 -1 (2500 750)(3500 750);
FORCEPROP 2 LAST SIG_NAME M_F_CPU1_SA_CS_N<3:0>
J 0
(2640 760);
DISPLAY 0.680851 (2640 760);
PAINT WHITE (2640 760);
WIRE 17 -1 (2500 700)(2500 750);
WIRE 17 -1 (2500 650)(2500 700);
WIRE 17 -1 (2500 600)(2500 650);
WIRE 17 -1 (2500 3500)(3500 3500);
FORCEPROP 2 LAST SIG_NAME M_F_CPU1_SA_DQS_DN<9:0>
J 0
(2640 3510);
DISPLAY 0.680851 (2640 3510);
PAINT WHITE (2640 3510);
WIRE 17 -1 (2500 3450)(2500 3500);
WIRE 17 -1 (2500 3400)(2500 3450);
WIRE 17 -1 (2500 3350)(2500 3400);
WIRE 17 -1 (2500 3300)(2500 3350);
WIRE 17 -1 (2500 3250)(2500 3300);
WIRE 17 -1 (2500 3200)(2500 3250);
WIRE 17 -1 (2500 3150)(2500 3200);
WIRE 17 -1 (2500 3100)(2500 3150);
WIRE 17 -1 (2500 3050)(2500 3100);
WIRE 17 -1 (2500 4050)(3500 4050);
FORCEPROP 2 LAST SIG_NAME M_F_CPU1_SA_DQS_DP<9:0>
J 0
(2640 4060);
DISPLAY 0.680851 (2640 4060);
PAINT WHITE (2640 4060);
WIRE 17 -1 (2500 4000)(2500 4050);
WIRE 17 -1 (2500 3950)(2500 4000);
WIRE 17 -1 (2500 3900)(2500 3950);
WIRE 17 -1 (2500 3850)(2500 3900);
WIRE 17 -1 (2500 3800)(2500 3850);
WIRE 17 -1 (2500 3750)(2500 3800);
WIRE 17 -1 (2500 3700)(2500 3750);
WIRE 17 -1 (2500 3650)(2500 3700);
WIRE 17 -1 (2500 3600)(2500 3650);
WIRE 17 -1 (2500 1250)(3500 1250);
FORCEPROP 2 LAST SIG_NAME M_F_CPU1_SB_CA<6:0>
J 0
(2640 1260);
DISPLAY 0.680851 (2640 1260);
PAINT WHITE (2640 1260);
WIRE 17 -1 (2500 1200)(2500 1250);
WIRE 17 -1 (2500 1150)(2500 1200);
WIRE 17 -1 (2500 1100)(2500 1150);
WIRE 17 -1 (2500 1050)(2500 1100);
WIRE 17 -1 (2500 1000)(2500 1050);
WIRE 17 -1 (2500 950)(2500 1000);
WIRE 17 -1 (2500 450)(3500 450);
FORCEPROP 2 LAST SIG_NAME M_F_CPU1_SB_CS_N<3:0>
J 0
(2640 460);
DISPLAY 0.680851 (2640 460);
PAINT WHITE (2640 460);
WIRE 17 -1 (2500 400)(2500 450);
WIRE 17 -1 (2500 350)(2500 400);
WIRE 17 -1 (2500 300)(2500 350);
WIRE 17 -1 (2500 2350)(3500 2350);
FORCEPROP 2 LAST SIG_NAME M_F_CPU1_SB_DQS_DN<9:0>
J 0
(2640 2360);
DISPLAY 0.680851 (2640 2360);
PAINT WHITE (2640 2360);
WIRE 17 -1 (2500 2300)(2500 2350);
WIRE 17 -1 (2500 2250)(2500 2300);
WIRE 17 -1 (2500 2200)(2500 2250);
WIRE 17 -1 (2500 2150)(2500 2200);
WIRE 17 -1 (2500 2100)(2500 2150);
WIRE 17 -1 (2500 2050)(2500 2100);
WIRE 17 -1 (2500 2000)(2500 2050);
WIRE 17 -1 (2500 1950)(2500 2000);
WIRE 17 -1 (2500 1900)(2500 1950);
WIRE 17 -1 (2500 2900)(3500 2900);
FORCEPROP 2 LAST SIG_NAME M_F_CPU1_SB_DQS_DP<9:0>
J 0
(2640 2910);
DISPLAY 0.680851 (2640 2910);
PAINT WHITE (2640 2910);
WIRE 17 -1 (2500 2850)(2500 2900);
WIRE 17 -1 (2500 2800)(2500 2850);
WIRE 17 -1 (2500 2750)(2500 2800);
WIRE 17 -1 (2500 2700)(2500 2750);
WIRE 17 -1 (2500 2650)(2500 2700);
WIRE 17 -1 (2500 2600)(2500 2650);
WIRE 17 -1 (2500 2550)(2500 2600);
WIRE 17 -1 (2500 2500)(2500 2550);
WIRE 17 -1 (2500 2450)(2500 2500);
WIRE 17 -1 (-1025 100)(-1025 150);
WIRE 17 -1 (-1025 150)(-1025 200);
WIRE 17 -1 (-1025 200)(-1025 250);
WIRE 17 -1 (-1025 250)(-1025 300);
WIRE 17 -1 (-1025 300)(-1025 350);
WIRE 17 -1 (-1025 350)(-1025 400);
WIRE 17 -1 (-1025 400)(-1025 450);
WIRE 17 -1 (-1950 450)(-1025 450);
FORCEPROP 2 LAST SIG_NAME M_F_CPU1_SB_CB<7:0>
J 0
(-1810 460);
DISPLAY 0.680851 (-1810 460);
PAINT WHITE (-1810 460);
WIRE 17 -1 (-1025 500)(-1025 550);
WIRE 17 -1 (-1025 550)(-1025 600);
WIRE 17 -1 (-1025 600)(-1025 650);
WIRE 17 -1 (-1025 650)(-1025 700);
WIRE 17 -1 (-1025 700)(-1025 750);
WIRE 17 -1 (-1025 750)(-1025 800);
WIRE 17 -1 (-1025 800)(-1025 850);
WIRE 17 -1 (-1025 850)(-1025 900);
WIRE 17 -1 (-1025 900)(-1025 950);
WIRE 17 -1 (-1025 950)(-1025 1000);
WIRE 17 -1 (-1025 1000)(-1025 1050);
WIRE 17 -1 (-1025 1050)(-1025 1100);
WIRE 17 -1 (-1025 1100)(-1025 1150);
WIRE 17 -1 (-1025 1150)(-1025 1200);
WIRE 17 -1 (-1025 1200)(-1025 1250);
WIRE 17 -1 (-1025 1250)(-1025 1300);
WIRE 17 -1 (-1025 1300)(-1025 1350);
WIRE 17 -1 (-1025 1350)(-1025 1400);
WIRE 17 -1 (-1025 1400)(-1025 1450);
WIRE 17 -1 (-1025 1450)(-1025 1500);
WIRE 17 -1 (-1025 1500)(-1025 1550);
WIRE 17 -1 (-1025 1550)(-1025 1600);
WIRE 17 -1 (-1025 1600)(-1025 1650);
WIRE 17 -1 (-1025 1650)(-1025 1700);
WIRE 17 -1 (-1025 1700)(-1025 1750);
WIRE 17 -1 (-1025 1750)(-1025 1800);
WIRE 17 -1 (-1025 1800)(-1025 1850);
WIRE 17 -1 (-1025 1850)(-1025 1900);
WIRE 17 -1 (-1025 1900)(-1025 1950);
WIRE 17 -1 (-1025 1950)(-1025 2000);
WIRE 17 -1 (-1025 2000)(-1025 2050);
WIRE 17 -1 (-1950 2050)(-1025 2050);
FORCEPROP 2 LAST SIG_NAME M_F_CPU1_SB_DQ<31:0>
J 0
(-1810 2060);
DISPLAY 0.680851 (-1810 2060);
PAINT WHITE (-1810 2060);
WIRE 17 -1 (-1025 2100)(-1025 2150);
WIRE 17 -1 (-1025 2150)(-1025 2200);
WIRE 17 -1 (-1025 2200)(-1025 2250);
WIRE 17 -1 (-1025 2250)(-1025 2300);
WIRE 17 -1 (-1025 2300)(-1025 2350);
WIRE 17 -1 (-1025 2350)(-1025 2400);
WIRE 17 -1 (-1025 2400)(-1025 2450);
WIRE 17 -1 (-1950 2450)(-1025 2450);
FORCEPROP 2 LAST SIG_NAME M_F_CPU1_SA_CB<7:0>
J 0
(-1810 2460);
DISPLAY 0.680851 (-1810 2460);
PAINT WHITE (-1810 2460);
WIRE 17 -1 (-1025 2600)(-1025 2650);
WIRE 17 -1 (-1025 2550)(-1025 2600);
WIRE 17 -1 (-1025 2650)(-1025 2700);
WIRE 17 -1 (-1025 2700)(-1025 2750);
WIRE 17 -1 (-1025 2500)(-1025 2550);
WIRE 17 -1 (-1025 2750)(-1025 2800);
WIRE 17 -1 (-1025 2800)(-1025 2850);
WIRE 17 -1 (-1025 2850)(-1025 2900);
WIRE 17 -1 (-1025 2900)(-1025 2950);
WIRE 17 -1 (-1025 2950)(-1025 3000);
WIRE 17 -1 (-1025 3000)(-1025 3050);
WIRE 17 -1 (-1025 3050)(-1025 3100);
WIRE 17 -1 (-1025 3100)(-1025 3150);
WIRE 17 -1 (-1025 3150)(-1025 3200);
WIRE 17 -1 (-1025 3200)(-1025 3250);
WIRE 17 -1 (-1025 3250)(-1025 3300);
WIRE 17 -1 (-1025 3300)(-1025 3350);
WIRE 17 -1 (-1025 3350)(-1025 3400);
WIRE 17 -1 (-1025 3400)(-1025 3450);
WIRE 17 -1 (-1025 3450)(-1025 3500);
WIRE 17 -1 (-1025 3500)(-1025 3550);
WIRE 17 -1 (-1025 3550)(-1025 3600);
WIRE 17 -1 (-1025 3600)(-1025 3650);
WIRE 17 -1 (-1025 3650)(-1025 3700);
WIRE 17 -1 (-1025 3700)(-1025 3750);
WIRE 17 -1 (-1025 3750)(-1025 3800);
WIRE 17 -1 (-1025 3800)(-1025 3850);
WIRE 17 -1 (-1025 3850)(-1025 3900);
WIRE 17 -1 (-1025 3900)(-1025 3950);
WIRE 17 -1 (-1025 3950)(-1025 4000);
WIRE 17 -1 (-1025 4000)(-1025 4050);
WIRE 17 -1 (-1950 4050)(-1025 4050);
FORCEPROP 2 LAST SIG_NAME M_F_CPU1_SA_DQ<31:0>
J 0
(-1810 4060);
DISPLAY 0.680851 (-1810 4060);
PAINT WHITE (-1810 4060);
WIRE 17 -1 (-1025 -50)(-1025 0);
WIRE 17 -1 (-1950 0)(-1025 0);
FORCEPROP 2 LAST SIG_NAME M_F_CPU1_CLK_DP<1:0>
J 0
(-1810 10);
DISPLAY 0.680851 (-1810 10);
PAINT WHITE (-1810 10);
WIRE 17 -1 (-1025 -150)(-1025 -100);
WIRE 17 -1 (-1950 -100)(-1025 -100);
FORCEPROP 2 LAST SIG_NAME M_F_CPU1_CLK_DN<1:0>
J 0
(-1810 -90);
DISPLAY 0.680851 (-1810 -90);
PAINT WHITE (-1810 -90);
WIRE 16 -1 (-925 1025)(-475 1025);
WIRE 16 -1 (-925 2425)(-475 2425);
WIRE 16 -1 (-925 2475)(-475 2475);
WIRE 16 -1 (-925 2525)(-475 2525);
WIRE 16 -1 (-925 2575)(-475 2575);
WIRE 16 -1 (-925 -125)(-475 -125);
WIRE 16 -1 (-925 -175)(-475 -175);
WIRE 16 -1 (-925 -25)(-475 -25);
WIRE 16 -1 (-925 -75)(-475 -75);
WIRE 16 -1 (-925 4025)(-475 4025);
WIRE 16 -1 (-925 3975)(-475 3975);
WIRE 16 -1 (-925 3925)(-475 3925);
WIRE 16 -1 (-925 3875)(-475 3875);
WIRE 16 -1 (-925 3825)(-475 3825);
WIRE 16 -1 (-925 3775)(-475 3775);
WIRE 16 -1 (-925 3725)(-475 3725);
WIRE 16 -1 (-925 3675)(-475 3675);
WIRE 16 -1 (-925 3625)(-475 3625);
WIRE 16 -1 (-925 3575)(-475 3575);
WIRE 16 -1 (-925 3525)(-475 3525);
WIRE 16 -1 (-925 3475)(-475 3475);
WIRE 16 -1 (-925 3425)(-475 3425);
WIRE 16 -1 (-925 3375)(-475 3375);
WIRE 16 -1 (-925 3325)(-475 3325);
WIRE 16 -1 (-925 3275)(-475 3275);
WIRE 16 -1 (-925 3225)(-475 3225);
WIRE 16 -1 (-925 3175)(-475 3175);
WIRE 16 -1 (-925 3125)(-475 3125);
WIRE 16 -1 (-925 3075)(-475 3075);
WIRE 16 -1 (-925 3025)(-475 3025);
WIRE 16 -1 (-925 2975)(-475 2975);
WIRE 16 -1 (-925 2925)(-475 2925);
WIRE 16 -1 (-925 2875)(-475 2875);
WIRE 16 -1 (-925 2825)(-475 2825);
WIRE 16 -1 (-925 2775)(-475 2775);
WIRE 16 -1 (-925 2725)(-475 2725);
WIRE 16 -1 (-925 2675)(-475 2675);
WIRE 16 -1 (-925 2625)(-475 2625);
WIRE 16 -1 (-925 2375)(-475 2375);
WIRE 16 -1 (-925 2325)(-475 2325);
WIRE 16 -1 (-925 2275)(-475 2275);
WIRE 16 -1 (-925 2225)(-475 2225);
WIRE 16 -1 (-925 2175)(-475 2175);
WIRE 16 -1 (-925 2125)(-475 2125);
WIRE 16 -1 (-925 2075)(-475 2075);
WIRE 16 -1 (-925 2025)(-475 2025);
WIRE 16 -1 (-925 1975)(-475 1975);
WIRE 16 -1 (-925 1925)(-475 1925);
WIRE 16 -1 (-925 1875)(-475 1875);
WIRE 16 -1 (-925 1825)(-475 1825);
WIRE 16 -1 (-925 1775)(-475 1775);
WIRE 16 -1 (-925 1725)(-475 1725);
WIRE 16 -1 (-925 1675)(-475 1675);
WIRE 16 -1 (-925 1625)(-475 1625);
WIRE 16 -1 (-925 1575)(-475 1575);
WIRE 16 -1 (-925 1525)(-475 1525);
WIRE 16 -1 (-925 1475)(-475 1475);
WIRE 16 -1 (-925 1425)(-475 1425);
WIRE 16 -1 (-925 1375)(-475 1375);
WIRE 16 -1 (-925 1325)(-475 1325);
WIRE 16 -1 (-925 1275)(-475 1275);
WIRE 16 -1 (-925 1225)(-475 1225);
WIRE 16 -1 (-925 1175)(-475 1175);
WIRE 16 -1 (-925 1125)(-475 1125);
WIRE 16 -1 (-925 1075)(-475 1075);
WIRE 16 -1 (-925 975)(-475 975);
WIRE 16 -1 (-925 925)(-475 925);
WIRE 16 -1 (-925 875)(-475 875);
WIRE 16 -1 (-925 825)(-475 825);
WIRE 16 -1 (-925 775)(-475 775);
WIRE 16 -1 (-925 725)(-475 725);
WIRE 16 -1 (-925 675)(-475 675);
WIRE 16 -1 (-925 625)(-475 625);
WIRE 16 -1 (-925 575)(-475 575);
WIRE 16 -1 (-925 525)(-475 525);
WIRE 16 -1 (-925 475)(-475 475);
WIRE 16 -1 (-925 425)(-475 425);
WIRE 16 -1 (-925 375)(-475 375);
WIRE 16 -1 (-925 325)(-475 325);
WIRE 16 -1 (-925 275)(-475 275);
WIRE 16 -1 (-925 225)(-475 225);
WIRE 16 -1 (-925 175)(-475 175);
WIRE 16 -1 (-925 125)(-475 125);
WIRE 16 -1 (-925 75)(-475 75);
WIRE 16 -1 (3500 875)(1975 875);
FORCEPROP 2 LAST SIG_NAME M_F_CPU1_SB_PAR
J 0
(2609 884);
DISPLAY 0.680851 (2609 884);
PAINT WHITE (2609 884);
WIRE 16 -1 (1975 2425)(2400 2425);
WIRE 16 -1 (1975 2475)(2400 2475);
WIRE 16 -1 (1975 2525)(2400 2525);
WIRE 16 -1 (1975 2575)(2400 2575);
WIRE 16 -1 (1975 2625)(2400 2625);
WIRE 16 -1 (1975 2675)(2400 2675);
WIRE 16 -1 (1975 2725)(2400 2725);
WIRE 16 -1 (1975 2775)(2400 2775);
WIRE 16 -1 (1975 2825)(2400 2825);
WIRE 16 -1 (1975 2875)(2400 2875);
WIRE 16 -1 (1975 1875)(2400 1875);
WIRE 16 -1 (1975 1925)(2400 1925);
WIRE 16 -1 (1975 1975)(2400 1975);
WIRE 16 -1 (1975 2025)(2400 2025);
WIRE 16 -1 (1975 2075)(2400 2075);
WIRE 16 -1 (1975 2125)(2400 2125);
WIRE 16 -1 (1975 2175)(2400 2175);
WIRE 16 -1 (1975 2225)(2400 2225);
WIRE 16 -1 (1975 2275)(2400 2275);
WIRE 16 -1 (1975 2325)(2400 2325);
WIRE 16 -1 (1975 275)(2400 275);
WIRE 16 -1 (1975 325)(2400 325);
WIRE 16 -1 (1975 375)(2400 375);
WIRE 16 -1 (1975 425)(2400 425);
WIRE 16 -1 (1975 925)(2400 925);
WIRE 16 -1 (1975 975)(2400 975);
WIRE 16 -1 (1975 1025)(2400 1025);
WIRE 16 -1 (1975 1075)(2400 1075);
WIRE 16 -1 (1975 1125)(2400 1125);
WIRE 16 -1 (1975 1175)(2400 1175);
WIRE 16 -1 (1975 1225)(2400 1225);
WIRE 16 -1 (3500 1375)(1975 1375);
FORCEPROP 2 LAST SIG_NAME M_F_CPU1_SA_PAR
J 0
(2609 1384);
DISPLAY 0.680851 (2609 1384);
PAINT WHITE (2609 1384);
WIRE 16 -1 (1975 3575)(2400 3575);
WIRE 16 -1 (1975 3625)(2400 3625);
WIRE 16 -1 (1975 3675)(2400 3675);
WIRE 16 -1 (1975 3725)(2400 3725);
WIRE 16 -1 (1975 3775)(2400 3775);
WIRE 16 -1 (1975 3825)(2400 3825);
WIRE 16 -1 (1975 3875)(2400 3875);
WIRE 16 -1 (1975 3925)(2400 3925);
WIRE 16 -1 (1975 3975)(2400 3975);
WIRE 16 -1 (1975 4025)(2400 4025);
WIRE 16 -1 (1975 3025)(2400 3025);
WIRE 16 -1 (1975 3075)(2400 3075);
WIRE 16 -1 (1975 3125)(2400 3125);
WIRE 16 -1 (1975 3175)(2400 3175);
WIRE 16 -1 (1975 3225)(2400 3225);
WIRE 16 -1 (1975 3275)(2400 3275);
WIRE 16 -1 (1975 3325)(2400 3325);
WIRE 16 -1 (1975 3375)(2400 3375);
WIRE 16 -1 (1975 3425)(2400 3425);
WIRE 16 -1 (1975 3475)(2400 3475);
WIRE 16 -1 (1975 575)(2400 575);
WIRE 16 -1 (1975 625)(2400 625);
WIRE 16 -1 (1975 675)(2400 675);
WIRE 16 -1 (1975 725)(2400 725);
WIRE 16 -1 (1975 1425)(2400 1425);
WIRE 16 -1 (1975 1475)(2400 1475);
WIRE 16 -1 (1975 1525)(2400 1525);
WIRE 16 -1 (1975 1575)(2400 1575);
WIRE 16 -1 (1975 1625)(2400 1625);
WIRE 16 -1 (1975 1675)(2400 1675);
WIRE 16 -1 (1975 1725)(2400 1725);
WIRE 16 -1 (3500 -75)(1975 -75);
FORCEPROP 2 LAST SIG_NAME M_F_CPU1_SB_RSP<0>
J 0
(2609 -66);
DISPLAY 0.680851 (2609 -66);
PAINT WHITE (2609 -66);
WIRE 16 -1 (3500 -25)(1975 -25);
FORCEPROP 2 LAST SIG_NAME M_F_CPU1_SB_RSP<1>
J 0
(2609 -16);
DISPLAY 0.680851 (2609 -16);
PAINT WHITE (2609 -16);
WIRE 16 -1 (3500 75)(1975 75);
FORCEPROP 2 LAST SIG_NAME M_F_CPU1_SA_RSP<0>
J 0
(2609 84);
DISPLAY 0.680851 (2609 84);
PAINT WHITE (2609 84);
WIRE 16 -1 (3500 125)(1975 125);
FORCEPROP 2 LAST SIG_NAME M_F_CPU1_SA_RSP<1>
J 0
(2609 134);
DISPLAY 0.680851 (2609 134);
PAINT WHITE (2609 134);
WIRE 16 -1 (3500 -175)(1975 -175);
FORCEPROP 2 LAST SIG_NAME M_F_CPU1_ALERT_N
J 0
(2609 -166);
DISPLAY 0.680851 (2609 -166);
PAINT WHITE (2609 -166);
QUIT
